M48
INCH,TZ
T01C.012
T02C.016
T03C.14
T04C.157
T05C.073
T06C.086
T07C.091
T08C.146
;LEADER: 12 
;HEADER: 
;CODE  : ASCII 
;FILE  : 14545-sa-1-8.drl for board 14545-sa.brd ... layers TOP and BOTTOM
;T01 Holesize 1. = 12.000000 Tolerance = +0.000000/-0.000000 PLATED MILS Quantity = 1305
;T02 Holesize 2. = 16.000000 Tolerance = +0.000000/-0.000000 PLATED MILS Quantity = 4172
;T03 Holesize 3. = 140.000000 Tolerance = +0.000000/-0.000000 PLATED MILS Quantity = 11
;T04 Holesize 4. = 157.000000 Tolerance = +0.000000/-0.000000 PLATED MILS Quantity = 2
;T05 Holesize 5. = 73.000000 Tolerance = +0.000000/-0.000000 NON_PLATED MILS Quantity = 30
;T06 Holesize 6. = 86.000000 Tolerance = +0.000000/-0.000000 NON_PLATED MILS Quantity = 10
;T07 Holesize 7. = 91.000000 Tolerance = +0.000000/-0.000000 NON_PLATED MILS Quantity = 12
;T08 Holesize 8. = 146.000000 Tolerance = +0.000000/-0.000000 NON_PLATED MILS Quantity = 2
%
G90
T01
X15750Y102250
X41999Y200050
X65999Y216050
X24300Y247300
X23399Y373931
X28100Y374000
X23499Y381831
X29599Y382884
X26299Y383854
Y387629
X29699Y388484
X23399Y389679
X23499Y397579
X29999Y398684
X26299Y399601
Y403376
X29899Y404384
X45800Y405200
X23600Y405700
X35900Y412600
X28900Y417800
X29365Y421169
X26399Y423322
X26524Y426720
X23399Y429051
X28900Y429200
X28800Y436700
X23499Y436951
X26492Y439350
X26599Y442749
X23399Y444799
X28700Y445700
Y451900
X61400Y452600
X23499Y452699
X26899Y454850
X65000Y455500
X26799Y458497
X23399Y460547
X29500Y460800
X26486Y462648
X26499Y466250
X23499Y468447
X67800Y469900
X64403Y471046
X64397Y474446
X68000Y475600
X23399Y476295
X26299Y478404
X26515Y481798
X23499Y484195
X68700Y485200
X64600Y486300
X64700Y489700
X68900Y490600
X23399Y492043
X28600Y499300
X23499Y499943
X26399Y501966
Y505741
X23399Y507791
X28600Y508500
X65599Y514250
X38400Y514900
X23499Y515691
X36499Y517775
Y521550
X23399Y523539
X35300Y524800
X26599Y525648
Y529302
X23499Y531439
X26900Y532800
X63499Y533050
X60003Y534150
X59999Y537550
X63499Y538550
X27199Y539600
X22800
X68000Y546500
X26199Y547176
X42867Y548450
X46299Y552950
X39217Y554750
X43099Y555850
X29999Y557150
X33307Y557938
X49799Y559150
X33699Y561850
X22999Y565550
X36499Y566350
X25581Y567763
X42599Y567850
X27699Y573750
X44959Y575756
X22699Y577950
X32800Y578200
X47543Y578340
X28000Y578500
X22978Y588571
X28808Y593150
X55499Y595650
X60076Y595777
X28700Y596549
X32200Y603710
X31598Y607102
X45701Y607700
X42202Y608195
X23999Y609250
X47626Y611300
X41400Y611500
X26800
X37999Y611550
X26869Y616861
X23499Y618053
X34976Y619250
X27499Y620203
Y623857
X30712Y624971
X42709Y625607
X23799Y625950
X39600Y626984
X47101Y632355
X38300Y633800
X23499Y633801
X57800Y634300
X41500Y635000
X52500
X29819Y634951
X26568Y635950
Y639604
X29999Y640550
X23399Y641649
X41500Y642800
X44900
X48999Y642900
X23499Y649549
X30999Y650550
X26737Y651957
X30999Y656250
X26999Y656550
X23725Y657471
X23499Y665297
X27687Y667447
Y671101
X23699Y673150
X23499Y681045
X27700Y682700
X23999Y689050
X29999Y694550
X25999Y694870
X50410Y695801
X50300Y699200
X27299Y783550
X35300Y789375
X45100Y793100
X35559Y795112
X37416Y799033
X44046Y799554
X56281Y801350
X32800Y803050
X46887Y803413
X51100Y806300
X37216Y807951
X37099Y811350
X49900Y813200
X31699Y814350
X26299Y815050
X54074Y815750
X65500Y817700
X46700Y820100
X62405Y820300
X39649Y822000
X46576Y832951
X49300Y836500
X29299Y836901
X58699Y837250
X68860Y838706
X40400Y840792
X63499Y843050
X69499Y842950
X48346Y844529
X24000Y853500
X29600Y854000
X25000Y858100
X26662Y861550
X23299Y863050
X29000Y896500
X63273Y1023974
X66499Y1025050
X63500Y1029600
X20400Y1048300
X8750Y1086250
X21817Y1156317
X20999Y1320550
Y1352050
X23700Y1354600
X25000Y1357742
X22999Y1366050
X25558Y1368447
X25507Y1372045
X22851Y1374169
X23499Y1381500
X27499Y1387550
X32333Y1389383
X24499Y1389663
X28499Y1391050
X33000Y1393000
X30500Y1395500
X33400Y1408100
X32451Y1411468
X28999Y1411550
X23999Y1413550
X30600Y1415100
X23499Y1421550
X23999Y1429050
X27999Y1430050
X33206Y1432352
X30499Y1434550
X22999Y1437050
X30999Y1438050
X26800Y1443800
X23499Y1445050
X36198Y1446749
X28697Y1448296
X32094Y1448448
X22999Y1453050
X29100Y1459200
X23499Y1460550
X30378Y1462518
X33915Y1462681
X34200Y1466200
X23028Y1468579
X23599Y1476350
X28999Y1478050
X34465Y1481683
X30999Y1482050
X23277Y1484050
X32700Y1485200
X24499Y1492050
X27100Y1494300
X30499Y1497550
X34099
X22999Y1500050
X34900Y1501000
X23799Y1508050
X30115Y1511900
X33512Y1512051
X35999Y1514550
X29600Y1515300
X22999Y1515550
X31999Y1517846
Y1521500
X35400Y1522200
X24199Y1523700
X24423Y1527123
X37999Y1530900
X29631Y1533063
X38500Y1534600
X26705Y1534795
X32099Y1535550
X30199Y1545450
X46700Y1546793
X25247Y1546912
X44299Y1550950
X34896Y1555730
X36340Y1558809
X24323Y1559950
X25521Y1563350
X31149Y1568300
X24900Y1569500
X38208Y1569841
X30520Y1572049
X27123Y1572205
X23608Y1572653
X39000Y1573500
X22699Y1594224
X34599Y1595300
X31099Y1595350
X33599Y1600200
X42199Y1601050
X23499Y1602050
Y1610050
X26999Y1610550
X32299Y1613524
X28899
X34884Y1615734
X23499Y1618050
X22999Y1626050
X32663Y1628181
X29499Y1630050
X34816Y1630953
X32199Y1633124
X23499Y1634050
X23415Y1641634
X26785Y1642089
X29626Y1645002
X33026Y1645051
X33100Y1648500
X23999Y1649550
X27499Y1657050
X23499
X28600Y1661039
X31999Y1661127
X34699Y1663300
X22999Y1665550
X29100Y1669500
X32494Y1669706
X32700Y1673300
X22864Y1673550
X24244Y1681868
X21600Y1702900
X47400Y1721700
X45877Y1724823
Y1728477
X47900Y1731300
X40400Y1735600
X43600Y1737100
X47000
X47800Y1740500
X41200Y1747050
X39000Y1750800
X42275Y1754000
X45799Y1757650
X47440Y1761391
X47400Y1765250
X43559Y1767884
X47604Y1769005
X45782Y1771877
X47499Y1775350
X46999Y1779550
X43751Y1780559
X39324Y1780623
X46199Y1783050
X35675Y1783450
X38094Y1785840
X30274Y1787238
X37699Y1789850
X31811Y1790271
X48049Y1791450
X42199Y1792250
X37574Y1794050
X46799Y1794900
X40478Y1795820
X32099Y1797150
X47899Y1798650
X38878Y1799571
X36300Y1805123
X35876Y1812350
X34129Y1815267
X29899Y1821050
X61009Y1822340
X34099Y1822850
X26099Y1824950
X36532Y1825352
X28550Y1828153
X36399Y1828750
X28123Y1831527
X43099Y1833850
X39699
X46499Y1836550
X22367Y1836633
X47166Y1839884
X60449Y1842550
X25999
X29599Y1844350
X40500Y1863000
X57999Y1891050
X48499Y1897050
X42499Y1902550
X28799Y1919060
X26765Y1921945
X23030Y1922038
X14999Y1936050
X8499Y1937550
X14999Y1940050
X44399Y1942250
X15099Y1944050
X50299Y1946650
X53999
X46565Y1946703
X38703Y1946754
X42532Y1946783
X34799Y1946750
X5303Y1947050
X44368Y1951450
X11703Y1951946
X25499Y1956050
X32999Y1960555
X17499Y1961050
X43462Y1961160
X50499Y1961550
X45999Y1971450
X31799Y1979050
X135999Y1881550
X123592Y1874254
X123393Y1870859
X137999Y1865151
Y1861497
X97999Y1843050
X80999Y1836550
X90000Y1827900
X93500
X96600Y1826000
X80099Y1817250
X86649Y1817100
X85599Y1797350
X101399Y1784700
X74400Y1778100
X99199Y1761899
X110099Y1759875
X89499Y1753575
X99999
X85341Y1752245
X85194Y1748848
X89306Y1746856
X107300Y1746300
X109499Y1743550
X109399Y1739550
X107100Y1736000
X112562Y1720613
X92479Y1718176
X112753Y1716613
X109499Y1712213
X117249Y1712090
X123749Y1711550
X135499Y1710150
X131999Y1710050
X104999Y1708963
X92873Y1708176
X117499Y1706050
X122642Y1704243
X128749Y1703300
X93999Y1703050
X133090Y1699959
X118499Y1694050
X74500Y1692000
X78100Y1688189
X92900Y1678176
X95499Y1665418
X74800Y1584700
X74700Y1574600
X80400Y1571766
X82329Y1568117
X78600Y1561900
X75000Y1561800
X85600Y1561500
X89373Y1561073
X96999Y1558050
X82429Y1555500
X79000
X97499Y1554550
X96200Y1550100
X100000Y1546650
X80043Y1544691
X83932Y1544705
X99899Y1539850
X90324Y1538800
X100800Y1536450
X98144Y1534309
X98599Y1491350
X100499Y1479650
X122199Y1476050
X123999Y1473050
X100699Y1471050
X124290Y1469241
X123808Y1465050
X127898Y1462441
X139235Y1460973
X105099Y1459150
X139815Y1454438
X106999Y1454450
X107999Y1448050
X104999Y1444941
X104935Y1440634
X107300Y1438100
X114499Y1432050
X76000Y1431100
X117390Y1429976
Y1426201
X114000Y1425400
X97000Y1377600
X97229Y1373337
X125100Y1366000
X110499Y1365050
X121000Y1364000
X112999Y1361550
X138000Y1359025
X112440Y1358196
X77758Y1357742
X129000Y1356500
X109999Y1355050
X113500Y1352000
X101500
X102350Y1348154
X113500
X89999Y1348050
X86890Y1346635
X113500Y1344500
X102350
X86890Y1342860
X102000Y1341000
X113000
X91279Y1340642
X107500Y1340500
X86165Y1339050
X119499
X109228Y1337090
Y1333315
X133475Y1331200
X107228Y1330552
X120507Y1328096
X116499Y1328013
X135850Y1322250
X102700Y1321363
X132999Y1319550
X120507Y1317050
X125999Y1315550
X78779Y1312664
X111499Y1311800
X107999Y1307713
X78779Y1302664
X119399Y1298113
X101399Y1292550
X116999Y1288050
X78613Y1282664
X78499Y1273550
X101541Y1262607
X103686Y1223863
X123970Y1221573
X118999Y1219050
X103999Y1216863
X130699Y1210653
X114999Y1210363
X106162Y1205702
X127000Y1202000
X76999Y1196550
X102900Y1196050
X106999Y1194550
X138600Y1124600
X127000Y1113500
X80500Y1104500
X112999Y1103740
X123999Y1102550
X116249
X108999Y1102050
X80500Y1097550
X132499Y1094550
X120749Y1093990
X125900Y1091282
X80000Y1090500
X105999Y1085800
X137100Y1084800
X121500Y1083600
X124423Y1081177
X137477
X105499Y1080550
X117499Y1079300
X137481Y1077557
X124423Y1077523
X106718Y1076050
X121100Y1075300
X101499Y1072550
X105600Y1069500
X116700Y1063500
X112699Y1058974
X123999Y1054050
X120100Y1053200
X123999Y1050650
X124100Y1047100
X75900Y1019100
X72000Y1013400
X75500Y1012261
X88000Y1008500
X80699Y1004450
Y1000450
X92600Y996100
X90000Y993100
X104700Y989900
X103200Y985364
X104600Y980500
X102100Y968500
X99000Y965000
X108200Y963600
X89499Y942850
X85999Y940429
X86399Y937050
X89400Y935400
X106749Y934367
X108845Y931657
X109099Y928250
X108441Y924705
X94999Y901550
X92499Y876550
X92999Y868550
X74220Y854150
X76540Y850938
X72362Y849550
X75500Y847700
X98700Y842600
X110499Y834550
X98000Y833500
X90500Y831500
X90000Y826000
X98700Y822550
X80500Y817000
X89000Y816500
X110202Y813379
X110195Y809979
X109831Y806598
X109700Y803200
X111200Y799450
X110700Y795700
X90700Y792900
X110500Y790200
X81999Y668050
X76999Y664550
X80499
X74499Y662050
X78499Y654050
X134300Y646400
X127999Y645550
X131400Y644600
X124999Y643050
X128600Y640500
X125499Y638950
X129000Y636600
X125499Y635550
X82499Y627050
X81251Y619251
Y607249
X107000Y604800
X105100Y600000
X138416Y553500
X137899Y545451
X72500Y545000
X106000Y543200
X109400
X88999Y538050
X86199Y536025
Y532250
X104502Y530552
X83700Y529500
X107526Y528996
X138999Y524213
X135499Y517550
X102100Y514900
X95500Y513400
X98900
X93200Y510500
X77499Y502550
X107499Y497050
X77999Y493050
X77499Y469550
X123300Y256000
X122397Y252688
X122799Y249150
X124999Y246050
X89800Y208550
X95350Y204550
X114900Y177900
X127999Y157050
X89800Y132400
X111790Y132259
X86899Y130567
X115876Y130050
X86599Y126750
X115876Y125973
X112999Y124050
X92999Y96128
X97499Y90050
X92999Y86128
X74499Y84050
Y80650
X78700Y74200
X74999Y74050
X78700Y70700
X74999Y70550
X92900Y66128
X93999Y58550
X205938Y72528
X178999Y79050
X174999
X175999Y82428
X175499Y86572
X176399Y94872
X186999Y99050
X201499Y104550
X205499Y105550
X207999Y109550
X188999Y120800
X173499Y149050
X152499Y149550
X197899Y165075
X173500Y166315
X149400Y166400
X154200Y168500
X149999Y239729
Y243504
X147099Y245350
X157440Y283924
Y303924
Y313924
X165500Y416500
X141499Y423050
X179700Y425800
X153459Y427494
X141499Y427550
X166500Y428500
X154101Y445550
X159600Y446399
X173100Y483100
X188000Y484500
X172499Y491053
X187699Y492850
X176799Y493850
X171722Y513827
X163549Y517100
X152000Y520813
X163449Y521650
X168453Y527949
X182499Y532550
X149000Y537500
X150750Y540416
X150500Y545000
X160932Y549468
X156500Y554000
X199900Y554050
X183499Y556100
X140940Y561800
X141300Y565900
X157000Y573851
X193549Y575875
X160824Y577000
X161000Y639100
X140900Y644000
X144238Y645356
Y649131
X140400Y649800
X158885Y679436
Y689436
X141500Y711000
X158385Y719436
X159500Y814700
X199000Y815000
X165499Y815550
X172660Y815731
X169106Y815865
X153900Y832200
X154799Y838050
X174199Y841050
X200539Y890300
X200799Y896600
X153499Y918550
X172500Y919294
X160399Y922850
X172000Y931600
X171100Y935000
X163500Y937100
X171000Y939500
X170250Y948500
X152500Y960000
X172000Y961000
X154749Y968249
X198924Y975975
X154749Y979149
X140800Y1076300
X159000Y1083000
X164700Y1085400
X157700Y1114948
X157600Y1124948
X148000Y1206000
X182500Y1275500
X149562Y1315987
X142667Y1319218
X147400Y1321600
X143700Y1332500
X140000Y1332600
X148024Y1333525
X199149Y1362900
X181000Y1365500
X180500Y1369900
X194700Y1385700
X150338Y1453958
X142999Y1456373
X142900Y1460000
X152499Y1462940
X157440Y1490460
Y1500460
Y1520460
Y1530460
X157400Y1596550
X160200Y1598500
X199500Y1627000
X186000Y1644000
X179999Y1644500
X195000Y1645500
X179999Y1655887
X171999Y1662250
X165575Y1676975
X152633Y1677967
X169600Y1682300
X181100Y1682700
X169100Y1685800
X177900Y1690400
X174250Y1694500
X150999Y1713550
X141500Y1715500
X141999Y1764550
X201499Y1781050
X165900Y1790500
X194049Y1792600
X161900Y1793400
X141800Y1860500
X141300Y1866400
X159421Y1925972
X264499Y1964050
X213138Y1952703
X210999Y1942050
X240964Y1934113
X220062Y1931113
X249499Y1928050
X213562Y1926113
X231999Y1914050
X257499Y1911050
X214999Y1909550
X249600Y1896800
X223436Y1890465
X232314Y1890513
X227814Y1887513
X231800Y1887100
X218100Y1886400
X236225Y1883125
X229800Y1875700
X276039Y1551300
X261999Y1516050
X232650Y1493450
X224750Y1483950
X233700Y1481600
X229025Y1471576
X241000Y1469600
X251500Y1136700
X269500Y1135500
X256000Y1133000
X255000Y1125700
X226800Y1093400
X247500Y1085500
X221300Y1083238
X229800Y1073600
X221800Y1069300
X233500Y1066100
X242000Y1066000
X215499Y905550
X229562Y904113
X211750Y894600
X236800Y765800
X241600Y765700
X228999Y765550
X218224Y765325
X277039Y740300
X279939Y728610
X230849Y726050
X252499
X213999Y725050
X254499Y697700
X249800Y689900
X216999Y686550
X249700Y682500
X238500Y680800
X246800Y677100
X220000Y516400
X233998Y357549
X239400Y357400
X224998Y357049
X213400Y355300
X252935Y319114
X231800Y318414
X214063Y318114
X253871Y291410
X213499Y283864
X250400Y283100
X225298Y281114
X239600Y278600
X250300Y275100
X247800Y269700
X218499Y190550
X233749Y110800
X223499Y108150
X237899Y107050
X213499Y104650
X245499Y100550
X246499Y86050
X210738Y82159
X246499Y80550
X210738Y78459
X230749Y76300
X210685Y74725
X215138Y72559
X210605Y70692
X225499Y68550
X210634Y66863
X210638Y62959
X305099Y17000
X311400Y17100
X296099
X317000Y17300
X343499Y31650
Y60150
X341499Y63050
Y67110
X308999Y87050
X282800Y87500
X324800Y89400
X291999Y94050
X297499Y97550
X315800Y100500
X323400Y105200
X293999Y293550
X298800Y333000
X326499Y334054
Y337454
X281499Y338550
X284999Y338650
X294500Y339000
X301249Y346050
X313039Y352350
X321900Y364600
X344520Y406329
X308999Y716450
X315999Y718950
X327999Y740550
X298000Y743500
X292999Y743650
X327749Y744050
X285499Y745050
X282099
X323249Y749010
X306500Y753550
X324959Y766750
X330540Y795509
X320499Y798050
X329499Y801550
X340699Y1046086
X345499Y1096550
X282500Y1135000
X345424Y1310050
X295000Y1513000
X347324Y1524000
X314999Y1527550
X326500Y1550200
X293700Y1553351
X289999Y1554650
X283499Y1556050
X279999
X330300Y1561200
X291400Y1561500
X297800Y1561600
X324000Y1562500
X312999Y1566050
X310249Y1569800
X323999Y1577250
X333000Y1578000
X349774Y1582900
X348499Y1762050
X313499Y1919050
X325221Y1927272
X285499Y1930050
X280689Y1942710
X342621Y1943409
X331622Y1944767
X342999Y1947409
X284999Y1947691
X288709Y1948042
X332103Y1948133
X329999Y1952273
X310499Y1957050
X315999Y1958550
X327100Y1966472
X330500Y1966500
X360000Y1967500
X367000Y1810000
X385499Y1735050
X353499Y1710450
X377900Y1703800
X354000Y1584900
X400999Y1575550
X354500Y1559500
X366149Y1554050
X390999Y1517798
Y1514398
X402499Y1476850
X370149Y1320050
X372999Y1123550
X364499Y1099050
X371500Y880600
X350499Y715050
X375999Y698550
X394649Y630600
X350499Y597300
X371999Y549300
X400499Y406329
X371700Y85500
X401499Y80550
X385999Y78050
X374499Y77550
X357503Y77043
X354999Y72050
X358999Y61550
X381999Y57050
Y53550
Y50150
X394199Y45050
X386799Y45000
X398799Y36152
X426000Y93500
X690249Y1805634
X659549Y1810634
X645549Y1815134
X644360Y1819137
X752500Y1954500
X764908Y1946592
X767999Y1945173
X758499Y1893550
X711848Y1825504
X755000Y1825000
X711652Y1822109
X707600Y1815600
X733049Y1814134
X732549Y1806634
X733149Y1798634
X750000Y1560500
X754000Y1551000
X767936Y1540336
X757999Y1484050
X758499Y1371050
X755600Y1149800
X764549Y1138500
X767083Y1134550
X757499Y1079550
Y745342
X762500Y734000
X766499Y732842
X758778Y345000
X768178Y333964
X763571Y295622
X827499Y163550
X813249Y163800
X820749Y163850
X839249Y164050
X821999Y193116
X833576Y215432
X829917Y216200
X837999Y219550
X822100Y261700
X809940Y264940
X816700Y274300
X827500Y274500
X836500Y274950
X822100Y279500
X812500Y282750
X770999Y290050
X785499Y291050
X770999Y295550
X777999Y296050
X786978Y298529
X770999Y302050
X827499Y313424
X772499Y323050
X772873Y326924
X780499Y330050
X791499Y333050
X784499Y334050
X789999Y336550
X820600Y664300
X829800Y666650
X808660Y667540
X813200Y675900
X835150Y677650
X806500Y687250
X771105Y722789
X781999Y725550
X791999Y733050
X769999
X784939Y733550
X788999Y736050
X825800Y1072300
X807000Y1072900
X815400Y1078800
X825700Y1083100
X814000Y1087000
X771999Y1124550
X772499Y1130050
X779499Y1131050
X792154Y1135926
X784439Y1136550
X789499Y1138050
X803199Y1151850
X822100Y1466800
X809960Y1478040
X814700Y1486300
X836625Y1487400
X827700Y1487600
X812550Y1494050
X784499Y1529050
X774542Y1530050
X774577Y1533796
X784577Y1535628
X771225Y1539474
X793999Y1541050
X791499Y1543550
X804899Y1556950
X774500Y1788000
X788000
X821249Y1791250
X811000Y1793000
X812000Y1799500
X793000Y1803500
X795849Y1805500
X822499Y1815164
X791999Y1819050
X770999Y1820550
X807000Y1822300
X803500Y1822708
X783499Y1827050
X822700Y1871100
X828500Y1877800
X810900Y1882440
X805900Y1887560
X812500Y1898500
X771499Y1936550
X782999Y1937050
X771499Y1940050
X794499Y1941050
X800431Y1941193
X785939Y1946800
X834799Y1946950
X792499Y1949050
X802499Y1951550
X802099Y1961950
X872086Y1935972
Y1925972
X857099Y1917650
X863699Y1906450
X871921Y1905972
X871421Y1895972
X859314Y1891365
X854814Y1883550
X850099Y1871056
X853499Y1871036
X854480Y1867578
X849999Y1867550
X863700Y1867300
X866914Y1865615
Y1861840
X865300Y1858700
X854905Y1825583
X849375Y1824982
X851500Y1821400
X879700Y1786300
X879664Y1782213
X873300Y1740100
X900500Y1721500
X886439Y1717600
X862800Y1712700
X889800Y1711500
X867523Y1542821
X867199Y1535150
X872086Y1530460
X871999Y1520460
X863699Y1501250
X871999Y1500460
X872086Y1490460
X858827Y1485696
X854327Y1477550
X848888Y1466402
X852288Y1466346
X852500Y1462600
X848861Y1462463
X874100Y1461600
X877853Y1459991
X878054Y1456450
X874900Y1454000
X866700Y1379796
X861849Y1376050
X866596Y1375796
X860799Y1358925
X864499Y1128750
X871499Y1124948
X872086Y1114948
X871999Y1094948
X872086Y1084948
X860133Y1084142
X852333Y1077716
X847233Y1061492
X850833Y1061441
X851000Y1058000
X847500Y1057800
X874733Y1055792
X877964Y1054485
X878233Y1051095
X874999Y1049550
X883083Y979183
X900999Y979050
X879708Y971892
X900499Y962100
X852696Y671197
X847772Y655370
X851172Y655432
X851300Y651700
X847600Y651600
X875300Y650500
X878596Y649348
Y645573
X875100Y644400
X879750Y570550
X879950Y565050
X902999Y556050
X868299Y336150
X867899Y321550
X886200Y313924
X886600Y303924
X868799Y294750
X865499Y288050
X871999Y283924
X842499Y280924
X858478Y274050
X872136Y273924
X854400Y264600
X847878Y250040
X851278Y249974
X850999Y246550
X847500Y246600
X874700Y244900
X878078Y243878
Y240103
X874900Y238600
X867500Y163924
X867576Y159924
X855500Y149500
X846500
X873000Y148500
X882499Y147050
X861999Y146550
X896999Y141550
X841499Y135550
X907499Y131800
X902499Y110550
X898999
X898800Y96000
X901499Y92050
X897555Y90494
X919800Y54600
X924200Y69800
X928461Y75981
X928457Y79885
X943499Y82550
X928428Y83714
X932961Y85581
X923761Y85550
X928508Y87747
X928561Y91481
X961499Y93350
X928561Y95181
X958999Y96050
X961499Y100050
X916499Y115050
X926999
X930999Y115550
X938499
X934499Y118750
X937999Y122050
X926999
X946899Y122550
X910999Y124550
X916499Y172550
X939549Y175175
X966499Y552050
X922049Y574375
X965999Y954550
X922049Y978575
X960900Y1636400
X969600Y1638300
X964000Y1639200
X971558Y1646500
X967600Y1651100
X977500Y1660500
X978000Y1668000
X974000Y1670700
X921549Y1788475
X917499Y1796550
X989900Y1678800
X987200Y1675600
X984211Y1667500
X989000Y1663802
X980800Y1659600
X988800Y1658300
X981500Y1653000
X982050Y1649302
X989502Y1646000
X986400Y1639302
X987029Y1634075
X990425Y1633898
X981200Y1625800
X987100Y1624900
X981200Y1618002
T02
X17600Y5604
X36000
X10000Y16500
X23499Y27050
X11499Y34050
X27799Y38450
X11999Y53550
X25799Y64050
X11999Y69050
X37000Y115300
X32400Y115400
X36900Y120900
X32300Y121000
X37000Y130700
X32100
Y136600
X36800Y136700
X11499Y142050
X19198Y152000
X19500Y161500
X15302
X11302
X6891Y161611
X11500Y166000
X15500
X19698
X7089Y166111
X30000Y179000
X36500
X23500
X36500Y188500
X24000
X30000
X23500Y198000
X29000
X35000Y198500
X23999Y229050
X23895Y238995
X23999Y243550
Y261050
X9499Y281550
Y301050
X8999Y318550
X15499Y328050
Y342550
Y360050
X26399Y750850
X14799Y751450
X8599Y751650
X39899Y754850
X27199Y764950
X39399Y768750
X17299Y773950
X10999Y774050
X28599Y775450
X26799Y874550
X8999Y889550
X26099Y891650
X8499Y907050
X25699Y916150
X8999Y926550
Y942050
X25099Y942150
X23899Y957950
X8999Y961550
X8499Y979050
X8999Y988550
X24799Y992250
X8499Y1006050
X33899Y1005950
X8999Y1025550
Y1041050
Y1060550
X8499Y1078050
X21500Y1092500
X17500
X6500Y1098000
Y1103500
Y1110000
Y1116500
X21500Y1122500
X18000Y1145500
X13000
X6500Y1146000
X17500Y1150500
X13000Y1151000
X7000Y1151500
X22500Y1164500
Y1170000
Y1176500
Y1183000
X23200Y1209300
X22447Y1223247
X22321Y1231121
X7999Y1264550
X7499Y1282050
X21799Y1282750
X21299Y1300250
X8799Y1302550
X8299Y1320050
X18099Y1343550
X9399Y1347350
X15399Y1708350
X7099Y1717750
X15299Y1723450
X7199Y1731450
X14899Y1736250
X15299Y1753250
X6099Y1753750
X30400Y1849650
X11299Y1850050
X23999Y1857950
X27199Y1874350
X38600Y1880200
X9099Y1881550
X31400Y1885200
X36100Y1892200
X8499Y1979550
X11500Y1987000
X26500
X61500Y1987500
X79500
X44500Y1987000
X55999Y1982550
X58999Y1958050
X73499Y1957050
X66499
X73499Y1945550
X62499Y1939550
X47499Y1930550
X62999Y1926050
X47499Y1915050
X62999Y1914550
X78999Y1904050
X78433Y1900010
X78999Y1896050
Y1891550
Y1887550
X52999Y1871550
X57499Y1871050
X78529Y1788113
X77165Y1759550
X74999Y1602050
X78999
X74999Y1598050
X78999
X74999Y1593550
X78999
X76999Y1528050
Y1519050
X76499Y1512050
Y1507050
Y1503050
Y1498050
X77166Y1353400
X77165Y1327335
X67000Y1011500
X65799Y994050
X72799Y982950
X77499Y962152
X77002Y952079
X76711Y948089
X77499Y921550
X76399Y820450
X70100Y818900
X79900Y791300
X53999Y791000
X67999Y790400
X39999Y742050
X44499
X39999Y738050
X43999Y737550
X40000Y733000
X44500
X40000Y729000
X44000Y728500
X53210Y701486
X47800Y692800
X43499Y657550
X52333Y641295
X61099Y603236
X72599Y578236
X39999Y576550
X42299Y564150
X49555Y563550
X62055Y561550
X75999Y556640
X70800Y540300
X77165Y514650
X75300Y454100
X67300Y450200
X68899Y445450
X76099Y414250
X39999Y359550
X52199Y342350
X39999Y342050
Y327550
X51099Y300050
X42999Y275650
X75299Y261750
X48499Y260550
Y243050
Y228550
X52499Y162550
Y145050
X78165Y137116
X52499Y130550
X71015Y123666
X77165Y110799
X59499Y108050
Y90550
Y76050
X65499Y59050
X50999Y47750
X40999Y42050
X65499Y41550
X40999Y27550
X65499Y27050
X50999Y21150
X73900Y6200
X55700Y5900
X90900Y5800
X107000Y6000
X90899Y14850
X97800Y36000
X88000Y36400
X92900Y39700
X96900Y40400
X93000Y44900
X96999Y49550
X92999Y52050
X116400Y56000
X114800Y68500
X95814Y136065
X96184Y151065
X117500Y162300
X96184Y166065
X97999Y199050
X92899Y231450
X86899Y242750
X93199Y279650
X84899Y289250
X90899Y309550
X94199Y325550
X93499Y337450
X95499Y355450
X89899Y368350
X89999Y396450
X87599Y403950
X95399Y416350
X89099Y426150
X99399Y437450
X93500Y445300
X97999Y445550
X97699Y449850
X93199
X100500Y456700
X94500Y456800
X97699Y477050
X93499
Y481550
X97699
X94499Y486550
X98999Y488050
X101500Y536500
X108599Y557236
X93100Y571640
X93599Y581236
X108900Y587600
X92599Y606236
X110800Y772700
X111299Y821050
X97800Y851800
X93808Y852063
X94001Y856895
X98001Y856950
X93299Y862050
X97499
X93900Y882400
X97900
X93690Y887139
X97700Y887400
X93499Y892050
X97499Y892550
X93499Y897152
X109500Y901100
X93000Y907165
X83988Y934028
X106500Y943000
X105300Y960300
X86900Y981600
X100999Y1095050
X105006Y1095366
X100999Y1099550
X105000Y1100500
X106999Y1114960
X110999Y1118050
X114999
X110999Y1122050
X114999
X110999Y1126050
X114999
X115200Y1130300
X110999Y1130550
X111999Y1188050
X102999
X100999Y1231032
X104999Y1231050
X117149Y1267550
X103499Y1305050
X93316Y1351000
X96000Y1369000
X96100Y1384650
X81499Y1589050
X92499
X86999
X83499Y1594050
Y1598050
Y1602050
X90999Y1624550
X85999
Y1628550
X90999
X91121Y1632549
X86299Y1632550
X118999Y1670550
X105749Y1712749
X84099Y1737150
X83599Y1744750
X117499Y1745050
X93499Y1759550
X94336Y1773113
X104417Y1791480
X104500Y1813400
X97999Y1815050
X116499Y1877550
X111499
Y1882550
X115999
X82999Y1887550
Y1891550
X83499Y1896050
X83999Y1900050
X83433Y1904010
X81499Y1915550
X98433Y1940510
X102433Y1940555
X103433Y1944510
X98999Y1944550
X83999Y1945050
X82499Y1957050
X92499Y1959050
X119499Y1972550
X115000Y1987000
X98000Y1987500
X146000
X128500
X132700Y1978600
X119999Y1978550
X126600Y1978500
X137900Y1978400
X126500Y1972400
X132700
X137900Y1972200
X159173Y1935972
X124999Y1912550
X129600Y1912400
X131100Y1908500
X124433Y1908510
X142499Y1905972
X141499Y1895972
X127499Y1889050
X122999
Y1883050
X126999Y1882550
X159054Y1881800
X143491Y1856400
X159054Y1855050
X157999Y1840972
X158000Y1825400
X142144Y1801644
X157500Y1797400
X120299Y1796150
X126599Y1789650
X137999Y1747723
X129999Y1747050
X123499
X144499Y1745550
X128000Y1735000
X133000Y1734500
X139500Y1730500
X130499Y1730050
X144499Y1729550
X122499Y1672550
X126562Y1670613
X122499Y1668550
X120100Y1633100
X124999Y1633050
X119999Y1629050
X124999
Y1620050
Y1616050
X159054Y1476200
X140799Y1435460
X157915Y1420460
X143199Y1412050
X156999Y1397750
X123500Y1360300
X145999Y1353050
X123938Y1267623
X126499Y1264550
X120499
X144149Y1230113
X148486
X120999Y1228550
X148499Y1226113
X144149
X121657Y1224604
X148499Y1222113
X144149
X128400Y1188600
X120999Y1188050
X141499Y1185550
X150999Y1181150
X151499Y1173050
X144399Y1171150
X145900Y1163200
X151699Y1158550
X133200Y1132100
X143200Y1116300
X134500Y1108100
X137900Y1103400
X139100Y1097100
X159055Y1070400
X151300Y1049300
X140864Y1044885
X159499Y1044579
X141234Y1029885
X158300Y1015000
X149499Y997650
X156499Y985950
X159186Y946117
X153299Y943750
X151999Y936550
X152499Y931550
X157499Y909050
Y904550
X159459Y896616
X155499Y896050
Y891050
X156499Y886950
X158114Y883290
X156499Y876050
Y870550
X155999Y863050
Y859050
X156999Y850050
X156499Y846050
X152499Y825050
Y820550
Y816050
Y810550
X139099Y707150
X131099Y700450
X159054Y665400
X152124Y651868
X152400Y643300
X140499Y626050
X143999Y605550
X140499Y600550
X140000Y587700
X154099Y529236
X147300Y526700
X147590Y521500
X145649Y509550
X136349Y509050
X153499Y502550
X148999
X136299Y499050
X140499
X134499Y488050
X139200Y484300
X135140Y478930
X154100Y476500
X135999Y472550
X149700Y471600
X130000Y452000
X128999Y445550
X133499Y445050
X137100Y436800
X129400Y426900
X124899Y409050
X126099Y396150
X152499Y395950
X139399Y372350
X134699Y356050
X130099Y326150
X130799Y300250
X135399Y277050
X157740Y273924
X158999Y259800
X152808Y246341
X133000Y240500
X142688Y218861
X143110Y203861
X131799Y201950
X155999Y181050
X124300Y167800
X123499Y149050
X133999
X144499
X132999Y141550
X142999Y141050
X152999
X123499Y140050
X127999Y99550
X158499Y93550
Y88550
Y84050
Y79050
X129999Y78050
X156499Y66050
X141999Y65550
X127499Y65050
X129100Y55900
X157299Y5150
X189499Y4550
Y39150
X197999Y39900
X193999
X167499Y43550
X194499Y44050
X183499Y45550
X192499Y57550
X166499Y79050
Y83550
X166999Y88050
Y92550
Y97050
X169999Y103050
X165499Y106050
X178700Y129900
X169300Y130300
X163499Y140050
X176499
X167499Y149550
X160999
X190199Y178650
X177899Y199250
X191999Y221550
X166800Y240800
X185999Y250550
X181299Y267350
X187199Y359050
X167299Y369350
X181599Y396250
X179649Y438550
X183999
Y442550
X179999
X183999Y447050
X179999
X164600Y476700
X171300
X190499Y487550
X194999Y490050
X191199Y491550
X190499Y507513
X187499Y531613
Y536113
X193499Y541113
X188999
Y545613
X193999Y545550
X188999Y549613
X193499
X181999Y609550
X162500Y623400
X181999Y624050
Y641550
X199199Y659150
X171999Y672450
X182599Y688350
X190399Y689050
X170799Y689150
X178899Y765250
X161999Y768050
X172599Y774250
X190699Y778350
X197099Y795050
X198199Y805950
X161999Y843550
X173899Y846550
X168499Y846713
X161999Y848050
X159999Y863050
X163999
X172099Y877450
X198499Y884113
X163499Y896550
X169299Y956350
X171499Y998650
X162499Y1023550
X163499Y1035050
X165600Y1057428
X169299Y1067150
X164999Y1075550
X168099Y1083550
X167999Y1092850
X199499Y1093850
X167499Y1118550
X167999Y1130550
X171599Y1139950
X163499Y1171650
X196499Y1196550
X180400Y1202800
X196499Y1215550
X181700Y1219900
X196499Y1224550
X196399Y1236650
X179800Y1244100
X195499Y1251050
X179500Y1262000
X195499Y1270050
Y1279050
X179999Y1292550
X175499
X179999Y1296613
X175823Y1297070
X179999Y1301550
X175499Y1302113
X179999Y1306050
X175499Y1306113
X195500Y1352500
X167499Y1389050
X178200Y1393400
X166799Y1409350
X180599Y1424050
X163499Y1433350
X180000Y1439500
X176599Y1447450
X165499Y1453550
X194200Y1457900
X172299Y1465850
X181500Y1479000
X166799Y1487450
X176299Y1500150
X195700Y1619100
X180000Y1619600
X195600Y1623700
X180299Y1626550
X179733Y1630590
X180299Y1634550
X199900Y1670600
X193499Y1674050
X181900Y1675300
X197600Y1694900
X195001Y1708150
X172499Y1714050
X167499Y1714113
X162499
X180701Y1716050
X195500Y1717000
X179701Y1724550
X195000Y1725500
X167999Y1726613
X163499
X172499
X165499Y1730613
X170499Y1731050
X180000Y1731000
X185999Y1746050
X199699Y1761450
X182299Y1801350
X173899Y1813250
X192100Y1813500
X168499Y1855550
X177599Y1866750
X167200Y1868000
X168299Y1879850
X199599
X181099Y1885850
X191599Y1891550
X163599Y1892050
X168899Y1960750
X190399Y1961250
X183999Y1968150
X199600Y1974900
X188199Y1978250
X183000Y1987500
X199000
X163500
X216999Y1987550
X236500Y1987500
X209699Y1978750
X225199
X221300Y1971200
X232999Y1971050
X227499
X238999Y1970550
X205499Y1968650
X226999Y1941050
X207199Y1892850
X212399Y1885850
X206999Y1867550
X224800Y1867000
X228999Y1856050
X204399Y1855450
X209999Y1825050
X215299Y1813950
X205199Y1801950
X238699Y1801850
X220799Y1791550
X221499Y1760950
X222499Y1743850
X237999Y1730550
X206900Y1726700
X222700Y1710100
X205200Y1708000
X201801Y1701450
X212000Y1701300
X235499Y1697050
X209901Y1691850
X220100Y1691700
X204400Y1688200
X216601Y1684350
X226800Y1684200
X213000Y1672500
X230600Y1670500
X237400Y1663800
X200600Y1663600
X228999Y1637550
X239400Y1624300
X209200Y1624000
X218000Y1614300
X238300Y1575100
X224499Y1575050
X231499
X211999Y1574550
X217999
X211999Y1568550
X230999Y1535550
X236999
X212899
X202399Y1500750
X213399Y1500300
X208999Y1491250
X204999Y1472650
X238899Y1453750
X226300Y1447800
X230899Y1437350
X212400Y1433700
X227999Y1421550
X204699Y1418350
X217999Y1408850
X201000Y1408500
X230599Y1400250
X203199Y1393250
X217499Y1387450
X208049Y1385550
X234300Y1375700
X227399Y1363050
X213199Y1350050
X226599Y1340250
X207699Y1337950
X219099Y1325950
X239099Y1314150
X202899Y1291450
X202199Y1276850
X232799Y1276150
X216300Y1274800
X211499Y1267050
Y1258050
X222299Y1251850
X229899Y1250550
X211499Y1239050
X221599Y1237250
X234299Y1232650
X220999Y1224350
X212499Y1212550
X201600Y1205900
X232599Y1195750
X212499Y1184550
X223099Y1182750
X210199Y1173450
X204199Y1163850
X214499Y1154250
X208199Y1145850
X209900Y1093600
X216499Y1053050
X215999Y1039550
X232499Y1038050
X202100Y1028100
X233999Y1012550
X217999Y1012050
X207299Y1008150
X217499Y998550
X233999Y997050
X206299Y990250
X232299Y981950
X217499Y981050
X205999Y978250
X216999Y967550
X233499Y966050
X213999Y958650
X225299Y957650
X206699Y953050
X214999Y948613
X219499
X214999Y944113
X219499Y943813
X203999Y943350
X214999Y939613
X219499
X204699Y929450
X214999Y926613
X219499
X215999Y887550
X220499
X232399Y886550
X215499Y883550
X209000Y846113
X204496Y846111
X208986Y842113
X204649
X208999Y838050
X204649
X217300Y816800
X233799Y806350
X208299Y805350
X227199Y795050
X214799Y774750
X234299Y773750
X224099Y770250
X208799Y766750
X209500Y759000
X226399Y677550
X212999Y677350
X218800Y668700
X234200Y668300
X219999Y647050
X207300Y639400
X219999Y632550
X206499Y623550
X224999Y613450
X206499Y609050
X220499Y577550
Y560050
Y545550
X205300Y508100
X224299Y494650
X218499Y474850
X232499Y461550
X231999Y445550
X209999Y426150
X237699Y426050
X220000Y421000
X232999Y414550
X209499Y412550
X217599Y396450
X223799Y365350
X209199Y365050
X201199Y266750
X235399Y263350
X217999Y250550
X203499
X210999Y221550
X232400Y220700
X227499Y192050
X231999
X227999Y187050
X231999
X227999Y182550
X231999
Y178050
X227999
X206899Y171650
X229099Y161350
X225499Y63550
Y58050
Y52550
Y46550
X199999Y46050
X208499Y45650
X206999Y5050
X226499
X261499Y4550
X241999Y5050
X278999
X245500Y39100
X245600Y43800
X247100Y47900
X246000Y52100
Y56500
Y61300
X246200Y65800
X246000Y70800
X244499Y122050
X274700Y131500
X244499Y136550
X244900Y149100
X262299Y164050
X262699Y208550
X271999Y216050
X265999Y245050
X249800Y248800
X267498Y295114
Y300114
Y305114
Y310114
X277799Y338599
X276299Y376050
X258999Y396650
X252499Y415050
X269999
X266699Y425050
X272499Y445050
X251499Y446050
X272999Y461050
X251999Y462050
X266199Y472350
X244199Y483350
X257499Y498050
X242099Y511750
X257499Y512550
Y530050
X244999Y545050
X277999Y545350
X244999Y559550
X256499Y577050
X244999
X256499Y591550
Y609050
X269499Y616550
Y631050
X244499Y632050
X257199Y640050
X245000Y647000
X269499Y648550
X246500Y663300
X268499Y701550
Y706550
Y711550
Y716550
X245599Y773450
X247099Y795050
X268099Y795450
X275299Y806350
X254699Y807650
X245399Y823550
X264499Y829050
X252399Y838250
X264999Y842550
X244099Y857450
X264999Y858450
X245199Y878050
X252899Y886350
X265799Y901850
X245399Y907450
X274299Y912950
X256199Y916250
X243899Y923650
X269599Y923950
X254899Y929250
X267199Y935350
X253499Y938050
X242199Y938750
X264799Y946850
X252499Y948850
X278799Y956150
X263299Y959350
X272999Y965550
X256499Y967050
X244199Y973250
X277599Y975250
X272999Y981050
X254499Y984550
X245899Y995250
X262499Y995850
X274999Y996550
X258999Y1011550
X274999Y1012050
X275099Y1024750
X269999Y1037050
X253499Y1038550
X253999Y1052050
X269999Y1052550
X272999Y1102850
X249499Y1104150
X274900Y1115600
X262499Y1129150
X276299Y1134550
X260349Y1139200
X272499Y1153050
X259999Y1152992
X268499Y1153050
X263999
X259499Y1161550
X271999
X263499
X267999
X251999Y1184550
X279799Y1191750
X242599Y1198350
X247899Y1208650
X242199Y1210050
X272999Y1214150
X261199Y1227950
X250900Y1248500
X264800Y1261300
X242900Y1263000
X274299Y1276450
X254899Y1289950
X241399Y1303250
X264799Y1313850
X252399Y1326350
X245999Y1339050
X265299Y1339650
X245999Y1358050
X263699Y1359550
X246499Y1370050
X265499Y1376950
X278799Y1386250
X249800Y1388400
X258999Y1396950
X270599Y1408550
X244999Y1412550
X278000Y1422000
X245499Y1424550
X259299Y1438750
X268499Y1453550
X250199Y1473550
X248000Y1482000
X247500Y1499000
X260999Y1503550
X279499Y1510550
X266999Y1512550
X279499Y1515050
X267349Y1518150
Y1522550
X279075Y1525957
X267349Y1527172
X278567Y1529925
X246200Y1617600
X278499Y1621550
X265700Y1635100
X258700Y1645100
X242999Y1658050
X270999Y1660550
X253999Y1676550
X273499Y1694050
X256499Y1710050
X255699Y1722550
X263499Y1734550
X249199Y1743150
X270599Y1748950
X244999Y1755050
X259499Y1760650
X252199Y1793050
X270599Y1801450
X253899Y1813250
X261499Y1825050
X255999Y1855950
X270299Y1867250
X241199Y1867150
X244700Y1878700
X241255Y1896055
X266999Y1915550
Y1920050
Y1924550
Y1929050
Y1933550
X240900Y1979000
X254500Y1987500
X272000
X291499Y1987550
X311500Y1987500
X289499Y1971050
X293999
Y1966550
X289499
X305500Y1965500
X293999Y1962050
X289499Y1961550
X306000Y1961500
X296858Y1956228
X293999Y1933050
X306999Y1932550
X302499
X298499
X281999Y1928550
Y1923550
X302499Y1922050
X281999Y1918550
X305999Y1913050
X314099Y1901250
X313599Y1889250
X308099Y1880550
X313599Y1870250
X295299
X298999Y1855950
X283999Y1856050
X316999Y1855950
X315499Y1812250
X284299Y1811150
X303999Y1800850
X286599Y1791850
X290699Y1760750
X303499Y1753550
X285499Y1742550
X297099Y1733850
X303999Y1722050
X280499Y1718550
X291099Y1707450
X299999Y1696050
X284300Y1676900
X318499Y1675550
X302399Y1662950
X316799Y1657450
X289000Y1641800
X307000Y1619600
X289998Y1578114
X293998
X289998Y1573614
X293998
Y1569114
X305998
X289998
X286700Y1516100
X312000Y1514600
X296599Y1497150
X312800Y1467400
X304699Y1457550
X286600Y1449700
X313600Y1442700
X300899Y1433350
X285499Y1427550
X312100Y1420700
X285499Y1418550
X303499Y1411250
X285499Y1399550
X301699Y1395750
X313600Y1391300
X301699Y1377950
X312900Y1366900
X286499Y1364050
X298099Y1357250
X286499Y1345050
X311900Y1344900
X297899Y1336150
X286799Y1326450
X311500Y1316300
X300499Y1305350
X281099Y1302850
X295399Y1292950
X312499Y1280350
X304699Y1265850
X283799Y1249250
X310299Y1240050
X300699Y1227350
X311999Y1213850
X286599Y1203750
X315408Y1202663
X300699Y1185150
X291399Y1174150
X313499Y1170150
X304499Y1156650
X283299Y1144850
X307999Y1142050
X317999Y1137550
X316499Y1124550
X290699Y1122650
X299499Y1113550
X283499Y1113050
X282999Y1099550
X299499Y1098050
X312299Y1093550
X304699Y1057050
X317699Y1054650
X299999Y1052350
X318299Y1038750
X303699Y1038050
X287099Y1035050
X289699Y1021750
X306399Y1020750
X298399Y1008150
X287099Y1000150
X304399Y997550
X294699Y989550
X285399Y982950
X306699Y981250
X298099Y977250
X288099Y971250
X307999Y970650
X299399Y965950
X289399Y963350
X290099Y948650
X310699Y943550
X281099
X315199Y925950
X302199Y914650
X287299Y901050
X302499Y899050
X297499Y884050
X281499Y883550
X280999Y870050
X315199Y869450
X297499Y868550
X283599Y857450
X304899Y856150
X313499Y847850
X293899Y843850
X280999Y843050
X300199Y835250
X280999Y827550
X288899Y820550
X318999Y814350
X307999Y803150
X287799Y794850
X307899Y794550
X290999Y767050
X294999
X290999Y762550
X294999
X306999Y758050
X290999
X294999
X315000Y754500
X280999Y717550
X296399Y716950
X280433Y713590
X280999Y705550
X308899Y705150
X298399Y703450
X280999Y701550
X297699Y681850
X307499Y679050
Y661550
X293999Y648050
X307499Y647050
X293999Y630550
X317999Y627850
X293999Y616050
X280999Y608550
X302899Y607950
X280999Y591050
Y576550
X307499Y573050
X296199Y568550
X307499Y555550
X297499Y551050
X307499Y541050
X281999Y529550
X297599Y519350
X309399Y513450
X281999Y512050
X298599Y501250
X281999Y497550
X312499Y484050
X292999Y483550
X306100Y462000
X286999Y462050
X291599Y446150
X300899Y431850
X303999Y415550
X284499Y415050
X310999Y396250
X289399Y395750
X299899Y376650
X289998Y361114
X293998
X289998Y356614
X293998
X305998Y352114
X293998
X289998
X313000Y313900
X316999Y312576
X279998Y308614
Y304114
Y299614
Y295114
X313199Y270350
X297999Y245050
X283499
X310499Y216550
X290999Y216050
X307199Y205550
X317499Y192950
X280999Y152050
X306100Y126500
X280999Y120050
X283599Y106250
X289499Y80550
X307999Y78550
X288499Y76550
X303999Y74050
X289999Y72550
X308499
X290999Y67550
X311299Y55450
X306999
X315799Y55350
X308800Y46400
X304500Y44500
X308900Y41000
X305100Y39700
X300700Y39400
X289499Y39050
X286603Y34928
X294100Y28000
X310499Y5050
X292999Y4550
X345499Y5050
X329999
X332200Y94200
X355999Y100550
X345999
X350999
X351999Y113050
X347499
X356499
X343399Y161350
X321799Y173950
X354099Y175350
X343999Y190050
X331499Y193250
X343799Y204550
X337999Y219050
X355499
X355999Y242750
X325499Y249450
X343499Y253550
X347699Y269050
X354999Y282550
X337499
X347399Y301950
X359399Y307250
X321748Y343299
X339399Y358050
X357999Y359050
X328799Y372350
X354099Y373050
X338399Y395650
X324999Y414550
X336099Y417550
X354699Y426650
X322099Y426850
X338899Y433850
X328599Y442250
X356399Y451750
X327900Y463200
X351399Y470750
X333499Y483050
X358399Y498650
X329999Y510450
X340799Y512050
X357399Y521250
Y530550
X321999Y533150
X341399Y535850
X331999Y540550
X357399Y543850
X321999Y550550
X331999Y555050
X341399Y558950
X357999Y559450
X321299Y565250
X331999Y572550
X359399Y576050
X320799Y582050
X340299Y586550
X359399Y599650
X328599Y602450
X342199Y613050
X359699Y627550
X328499Y635650
X342099Y646350
X331999Y646550
X358899Y657150
X331999Y661050
X341899Y664950
X359399Y669450
X331999Y678550
X342599Y678850
X359199Y690650
X324599Y696150
X345399Y698950
X357699Y707750
X330799Y712450
X341399Y715050
X355999Y752850
X347699Y773450
X353999Y787750
X338099Y811650
X338599Y821650
X325599Y823950
X338599Y840450
X323799Y859850
X330299Y871850
X323099Y885050
X340099Y887350
X321099Y899650
X338399Y901050
X340099Y910350
X322099Y913650
X331099Y923650
X340399Y931250
X328099Y937250
X340099Y952850
X323499Y956950
X329799Y970650
X333099Y983450
X320999Y997250
X321299Y1012450
X331299Y1017150
X321299Y1024750
X331599Y1028750
X329599Y1040750
Y1057050
X319999Y1066950
X339599Y1081550
X329299Y1098550
X326599Y1112350
X332999Y1123050
Y1138550
X323999Y1153250
X329799Y1182750
X328999Y1200550
X326649Y1218850
Y1227850
X327999Y1255050
X333349Y1270500
Y1288900
Y1307000
Y1332800
X344399Y1338150
X343599Y1360050
X333349Y1363500
Y1393100
X344099Y1393750
Y1421150
X333349Y1429500
X344099Y1449550
X333349Y1481900
X332500Y1519700
X351899Y1570850
X344500Y1583600
X350600Y1610900
X349099Y1634550
X337199Y1636350
X320299Y1642950
X335767Y1662735
X351099Y1691150
X334399Y1691650
X352000Y1700400
X320999Y1706050
X329999Y1716950
X321999Y1733050
X359499Y1736850
X343899Y1752650
X326301Y1766030
X321499Y1772550
X327299Y1791850
X357999Y1796050
X334999Y1797050
X322299Y1802150
X355699Y1810750
X351999Y1855450
X337499Y1855950
X336799Y1869950
X326399Y1876250
X348999Y1879050
X336799Y1888950
X326399Y1895250
X336799Y1897950
X348999Y1898050
X326899Y1907250
X349499Y1910050
X335799Y1916450
X358999Y1925050
X347999Y1925550
Y1944550
X348499Y1956550
X347699Y1972250
X326799Y1977050
X345499Y1987550
X329999
X382499
X364999Y1987050
X399299Y1976750
X385099Y1975950
X367299Y1972950
X388499Y1959550
X367299Y1956950
X388499Y1950550
X367999Y1940250
X388499Y1932950
X369199Y1919750
X389499Y1913050
X359999Y1906550
X389499Y1904050
X369999Y1901950
X359999Y1897550
X389499Y1885050
X369799Y1880050
X359999Y1878550
X369499Y1855950
X391499
X387899Y1802850
X393999Y1784550
X376499Y1775550
X393499Y1759550
X376799Y1734050
X380099Y1709650
X377099Y1696350
X374999Y1656750
X377700Y1629000
X375099Y1608250
X376099Y1572850
X374099Y1554550
X374799Y1491250
X373099Y1456550
X376299Y1437650
X373499Y1430050
Y1421050
Y1402050
X374499Y1375550
Y1366550
Y1347550
X375599Y1323350
X376599Y1293950
X376499Y1264550
Y1255550
Y1236550
X377499Y1210050
Y1201050
Y1182050
X373500Y1089500
X375000Y1034000
X374500Y973500
X375000Y939000
X360399Y615550
X368299Y386350
X380599Y381050
X394899Y357750
X386599Y348450
X383299Y310250
X386899Y299250
X369499Y282550
X382999Y276650
X381999Y254050
X362499Y253550
X387599Y220150
X369999Y219050
X385999Y207250
X382499Y190550
X362999Y190050
X389299Y161650
X363999Y153550
X381299Y136750
X363999Y136050
X360999Y113050
Y100550
X389599Y90950
X381499Y70050
X376999
Y65550
X381499
X369999Y23550
X382499Y20050
X369999Y19050
X371999Y15550
X380999
X376499
X395999Y5550
X382499Y5050
X364999Y4550
X413499Y6050
X432999
X416999Y25050
X436499Y31350
X417499Y46550
X436499Y50350
X416999Y63550
X437499Y71350
X417499Y79050
Y93550
Y108050
X400499Y119550
X417499Y125550
X400499Y134050
X416999Y145050
X400499Y151550
X416999Y164050
X417999Y185050
X430499Y217050
X423799Y259750
X437499Y275050
X412999Y275550
X437499Y289550
X412999Y290050
X437499Y307050
X412999Y307550
X422499Y348150
X422199Y363350
X438999Y381550
X420199Y391350
X426599Y415350
X415099Y422550
X410799Y431150
X419599Y458550
X431099Y479350
X415999Y518550
X435499Y519050
X430099Y551450
X427999Y565550
Y580050
Y597550
X427499Y624550
X420199Y638550
X437299Y744650
X435299Y763150
X424999Y766550
X435299Y777650
X422999Y785050
X435299Y795150
X422999Y799550
X434799Y814650
X422999Y817050
X434799Y833650
X422499Y836550
Y855550
X418799Y877050
Y896050
X423299Y994050
Y1013050
X424299Y1034050
X432599Y1064550
X433599Y1085550
X409499Y1102550
X428999
X439499Y1115550
X419999
X436999Y1128050
Y1142550
X437599Y1150050
X415499Y1161550
Y1176050
X416099Y1183550
X419499Y1219550
Y1234050
X420099Y1241550
X424999Y1259550
Y1278550
X425499Y1290550
X428499Y1325350
X416699Y1342650
X434499Y1360250
X416199Y1367550
X422299Y1394950
X426799Y1416050
X423299Y1430350
X425799Y1447950
X427099Y1469150
X414799Y1532350
X424299Y1541350
X439599Y1552150
X418299Y1561250
X434500Y1579500
X415999Y1603250
X431999Y1605550
X432499Y1617550
X416199Y1625250
X425499Y1635050
X414799Y1653750
X427499Y1662050
X414399Y1678350
X432400Y1680100
X428600Y1691200
X414499Y1707250
X435300Y1715300
X429499Y1748050
X436799Y1772550
X410757Y1772872
X422999Y1778550
X417799Y1790850
X414499Y1810450
X426499Y1855450
X406999Y1855950
X406499Y1874050
X434299Y1876050
X421399Y1888050
X406499Y1893050
X434299Y1895050
Y1904050
X406999Y1905050
X421399Y1907050
Y1916050
X405499Y1920550
X433299Y1922550
X420399Y1934550
X405499Y1939550
X433299Y1941550
Y1950550
X405999Y1951550
X420399Y1953550
Y1962550
X436299Y1977250
X420799
X403500Y1987000
X420500
X438999Y1987550
X456500Y1987500
X476000Y1987000
X473299Y1977250
X455799Y1976750
X459299Y1966850
Y1957850
X445999Y1954550
X475199Y1951950
X445999Y1945550
X475199Y1942950
X459299Y1938850
X445999Y1926550
X475199Y1923950
X460299Y1920350
Y1911350
X446999Y1908050
X476199Y1905450
X446999Y1899050
X476199Y1896450
X460299Y1892350
X446999Y1880050
X476199Y1877450
X443999Y1855950
X464999Y1855450
X448099Y1809450
X445499Y1792550
X472699Y1792150
X463999Y1772050
X441499Y1758050
X458499Y1742050
X468499Y1712550
X448399Y1699450
X467999Y1696050
Y1687050
X447699Y1682850
X467999Y1668050
X449599Y1656950
X460199Y1632850
X472499Y1620550
X443799Y1612250
X472499Y1611550
X465999Y1603450
X449199Y1579050
X472299Y1572050
X452199Y1550650
X474299Y1544750
X461399Y1541650
X444299Y1532650
X466999Y1530650
X459699Y1468050
X478299Y1464850
X445099Y1464250
X456399Y1445950
X441499Y1431550
X459999Y1424050
X441499Y1414050
X464199Y1401450
X441499Y1399550
X466699Y1378150
X444899Y1377950
X468699Y1362850
X473999Y1342450
X448099Y1341250
X468999Y1323950
X465499Y1293550
Y1284550
X443799Y1274250
X465499Y1265550
X443799Y1265250
Y1246250
X443199Y1238750
Y1224250
X474099Y1165550
X454499Y1161550
X473099Y1144550
X453499Y1140550
X454999Y1115550
X474499Y1115050
X444499Y1102550
X463999Y1102050
X463499Y1083850
X462499Y1062850
Y1043850
X461999Y985050
Y966050
X462499Y946550
X443599Y945650
X462499Y929050
X442599Y924650
X462499Y914550
X442599Y905650
X464499Y896050
X462999Y884050
X475699Y880450
X462999Y865050
X479599Y847550
X453399Y826950
Y807950
X468699Y788350
X452099Y781450
X467699Y772750
X452099Y762450
X472999Y736550
X451099Y711650
X463999Y691550
X444799Y687350
X463999Y674050
X450399Y672750
X463999Y659550
X452499Y597050
Y579550
Y565050
X456499Y518050
X453999Y509550
X471499Y493950
X454499Y490050
Y472550
X440099Y459250
X454499Y458050
X472499
X443199Y440850
X454999Y438550
X453999Y417550
X468799Y414250
X450300Y404200
X458499Y382050
X443499Y354050
X464499Y353050
X466399Y304950
X479299Y297250
X463999Y283550
X444499Y283050
X448999Y255550
X469999Y254550
X449999Y217050
X472999Y214550
X446799Y205650
X445799Y184650
X474099Y181050
X445799Y165650
X473099Y160050
X442799Y142450
X473099Y141050
X471399Y124550
X441799Y121450
X470399Y103550
X441799Y102450
X470399Y84550
X466799Y64750
X465799Y43750
Y24750
X448499Y6050
X467999Y5550
X485499Y6050
X498999
X516499Y6550
X499999Y25550
X500499Y47050
X499999Y64050
X500499Y79550
Y94050
Y108550
Y126050
X499999Y145550
Y164550
X483599Y179350
X504199Y193250
X502899Y217150
X488999Y254550
X508499Y255050
X495999Y283550
X481499
X515499Y284050
X516899Y306950
X483499Y353050
X502999Y353550
X485000Y373200
X509999Y382550
X484900Y394700
X490999Y412550
X518999Y416550
X503699Y419250
X490999Y427050
Y444550
X511299Y449150
X490499Y464050
X498399Y470050
X519499Y471550
X490499Y483050
X519499Y489050
X508699Y498950
X491499Y504050
X518999Y508550
X485299Y534550
X514499Y546050
X504499Y566050
X479999Y566550
X504499Y580550
X479999Y581050
X504499Y598050
X479999Y598550
X509999Y640550
Y655050
X488499Y659050
X509999Y672550
X488499Y673550
Y691050
X506599Y711650
X487299Y716950
X490299Y734550
X489599Y752450
X511199Y782050
X495999Y795050
X493999Y813550
X512899Y823550
X493999Y828050
X512899Y842550
X493999Y845550
X493499Y865050
X510899Y868150
X493499Y884050
X485799Y901050
X506899Y900950
Y919950
X485799Y920050
X486799Y941050
X516499Y957050
X514499Y975550
Y990050
X493099Y996350
X514499Y1007550
X494099Y1017350
X513999Y1027050
Y1046050
X483499Y1064850
X484499Y1085850
X481499Y1102550
X501499
X518999Y1103050
X511999Y1115550
X491999
X504399Y1132250
X505399Y1153250
X486499Y1196050
X506599Y1202350
X486499Y1210550
X506599Y1216850
X487099Y1218050
X507199Y1224350
Y1243350
Y1252350
X498299Y1323350
X518499Y1346950
X499199Y1350550
X485599Y1367550
X508599Y1370550
X498899Y1386450
X481499Y1402550
X498899Y1408350
X481499Y1417050
X516999Y1418050
X500899Y1434350
X516999Y1437050
X517499Y1449050
X482599Y1449950
X505899Y1466250
X518899Y1530150
X488299Y1531050
X499699Y1538950
X502199Y1566250
X510100Y1579800
X484200Y1579900
X487099Y1606250
X508199Y1610450
X501399Y1634550
X484999Y1636550
X518499Y1643950
X509199Y1660550
X483599Y1662550
X507399Y1683350
X485599Y1694850
X502899Y1709650
X480999Y1756050
X508200Y1758200
X515499Y1779050
X484999
X496999Y1799550
X481299Y1811150
X514199Y1815750
X499999Y1854950
X517499Y1855450
X480499
X519399Y1876750
X492999Y1878050
X505799Y1893050
X519399Y1895750
X492999Y1897050
X519399Y1904750
X493499Y1909050
X505799Y1912050
Y1921050
X518399Y1923250
X491999Y1924550
X504799Y1939550
X518399Y1942250
X491999Y1943550
X518399Y1951250
X492499Y1955550
X504799Y1958550
Y1967550
X493799Y1977250
X509299
X492500Y1987500
X511999Y1987550
X531500Y1987500
X553499Y1987050
X546299Y1977250
X528799Y1976750
X546999Y1966850
X532499Y1958550
X546999Y1957850
X532499Y1949550
X546999Y1938850
X532499Y1930550
X547999Y1920350
X533499Y1912050
X547999Y1911350
X533499Y1903050
X547999Y1892350
X533499Y1884050
X538999Y1855950
X554499
X531799Y1818450
X555500Y1802700
X526499Y1801150
X539499Y1788150
X544300Y1784638
X532499Y1763050
X522300Y1739200
X556199Y1727050
X538299Y1721050
X555899Y1706750
X532999Y1700550
X555399Y1689350
X532499Y1688550
X555199Y1674750
X532499Y1669550
X532599Y1655650
X554199Y1651950
X532499Y1635550
X553399Y1624550
X529499Y1616550
X528999Y1604550
X552099Y1601950
X552199Y1576650
X533800Y1575500
X529799Y1555050
X538999Y1528350
X546099Y1467550
X528499Y1460250
X557499Y1452050
Y1443050
X536799Y1436350
X557499Y1424050
X538799Y1409750
X523999Y1391050
X540399Y1382150
X523499Y1379050
Y1360050
X545099Y1355250
X559099Y1343250
X555699Y1322950
X549399Y1302850
X530499Y1297050
X549399Y1293850
X527499Y1278150
X549399Y1274850
X548799Y1267350
X525999Y1263050
X548799Y1252850
X525999Y1245550
Y1231050
X547099Y1230750
Y1221750
X527999Y1212550
X547099Y1202750
X527499Y1200550
X546499Y1195250
X527499Y1181550
X546499Y1180750
X529499Y1116050
X548999
X553999Y1103050
X538499
X558499Y1088050
X535599Y1069550
X558499Y1069050
X558999Y1049550
X534599Y1048550
X558999Y1032050
X541899Y1021450
X558999Y1017550
X540899Y1000450
Y981450
X540299Y956850
X539299Y935850
X521999Y914550
Y895550
X522499Y876050
X541399Y873450
Y854450
X526499Y851150
X534499Y805950
X547499Y799050
Y780050
X525499Y772450
X547999Y760550
X527499Y747150
X547999Y743050
Y728550
X549999Y710050
X534499Y672050
Y654550
Y640050
X554499Y624550
X558699
X558709Y620245
X554499Y620050
X558499Y616050
X554304Y615840
X558499Y562550
X538999Y562050
X535499Y545050
X555999Y504550
X539299Y485550
X556499Y485050
Y467550
X539799Y466050
X538799Y445050
X555999Y412550
X530999Y381550
X548100Y362200
X520499Y353550
X558099Y335050
X557933Y331010
X557999Y326550
Y322550
X540099Y306550
X544799Y293950
X536499Y283050
X525999Y255050
X540499
X552999Y217550
X533499
X528799Y199950
X542499Y185050
X541499Y164050
X521299Y162450
X541499Y145050
X520299Y141450
X541999Y125550
X520299Y122450
X541999Y108050
Y93550
X523899Y85350
X541999Y79050
X522899Y64350
X541499Y63550
X541999Y46550
X522899Y45350
X541499Y25050
X551499Y6550
X535999
X570999Y6050
X588499Y6550
X587999Y25050
X588499Y46550
X587999Y63550
X568099Y72550
Y91550
X569099Y112550
X588499Y125550
X562799Y127750
X587999Y145050
X562799Y146750
X587999Y164050
X563799Y167750
X588999Y185050
X565999Y199950
X587999Y217050
X568499Y217550
X572999Y255050
Y269550
Y287050
X572499Y306550
Y325550
X599299Y344650
X573499Y346550
X579899Y375750
X599799Y385150
X592999Y407550
X577399Y420050
X592999Y422050
Y439550
X578399Y441050
X592499Y459050
X577899Y460550
X592499Y478050
X576099Y481850
X593499Y499050
X577099Y502850
X576599Y522350
X579499Y561550
X595999Y609550
Y624050
Y641550
X573499Y658550
Y673050
X597999Y690050
X573499Y690550
X565699Y710650
X586299Y711250
X577999Y732050
X575999Y750550
Y765050
Y782550
X575499Y802050
Y821050
X576499Y842050
X578299Y895650
X562999Y898050
X578299Y914650
X560999Y916550
Y931050
X570899Y946850
X560999Y948550
X583299Y961450
X570899Y965850
X560499Y968050
X583299Y980450
X571899Y986850
X560499Y987050
X560999Y999050
X598999Y1020550
Y1035050
X573499Y1036550
X598999Y1052550
X573499Y1055550
X598499Y1072050
X574499Y1076550
X598499Y1091050
X568499Y1101550
X588499
X578999Y1114550
X598999
X564499Y1116050
X567999Y1187550
X597599Y1196050
X567999Y1206550
X596599Y1215050
X567999Y1215550
X582699Y1233250
X565999Y1234050
X582699Y1247750
X565999Y1248550
X583299Y1255250
X598499Y1261550
X566399Y1273850
X583299Y1274250
X598499Y1280550
X583299Y1283250
X598999Y1292550
X579299Y1300750
X561099Y1301050
X599499Y1351550
X581999Y1370150
X599499Y1370550
X580999Y1412750
X575699Y1438950
X582999Y1461250
X590599Y1483450
X563499Y1486550
Y1492050
Y1497550
Y1503550
X582299Y1534150
X599799Y1544650
X567999Y1549950
X588099Y1572050
X573400Y1577600
X588000Y1604000
X569499Y1610550
Y1619550
X590799Y1627850
X580799Y1646150
X593399Y1668850
X572999Y1675550
X590599Y1694450
X572999Y1694550
Y1703550
X580299Y1722550
X582599Y1740050
X593299Y1760950
X560399Y1792550
X595199Y1820910
X573999Y1855450
X591499Y1855950
X562599Y1874450
X588899Y1882350
X575999Y1888050
X562599Y1893450
X588899Y1901350
X562599Y1902450
X575999Y1907050
X588899Y1910350
X576499Y1919050
X561599Y1920950
X587899Y1928850
X574999Y1934550
X561599Y1939950
X587899Y1947850
X561599Y1948950
X574999Y1953550
X587899Y1956850
X575499Y1965550
X570299Y1976250
X585799
X588499Y1986550
X568999Y1987050
X605999
X626999
X622799Y1976250
X605299Y1975750
X615499Y1968550
X601799Y1961850
X615499Y1959550
X601799Y1952850
X629699Y1947250
X615499Y1940550
X629699Y1938250
X601799Y1933850
X616499Y1922050
X629699Y1919250
X602799Y1915350
X616499Y1913050
X602799Y1906350
X630699Y1900750
X616499Y1894050
X630699Y1891750
X602799Y1887350
X630699Y1872750
X627499Y1855950
X611999
X627494Y1829068
X632799Y1820450
X608599Y1810750
X633837Y1807384
X619499Y1803150
X626999Y1800050
X627273Y1793905
X606999Y1745550
X625499Y1725050
X607599Y1716450
X609499Y1692050
X635099Y1691150
X609499Y1675050
X627299Y1659550
X600599Y1645450
X628499Y1636650
X612499Y1615550
X633499Y1615450
X635500Y1603900
X611999Y1603550
X611900Y1577900
X639200Y1576200
X623499Y1564050
X617699Y1530350
X610899Y1496750
X625199Y1489150
X636799Y1461250
X601299Y1447650
X626799Y1432350
X604899Y1407750
X627499Y1406050
X625499Y1383450
X599999Y1382550
X617899Y1360850
X632499Y1347950
X606199Y1338250
X605599Y1326350
X631799Y1322650
X608899Y1305050
X618199Y1296250
X638999Y1295550
X618199Y1287250
X638999Y1286550
X618199Y1268250
X638999Y1267550
X617599Y1260750
Y1246250
X630499Y1243950
X600899Y1238650
X626199Y1183450
X628699Y1164550
X603899Y1157850
X627699Y1143550
X616499Y1115050
X633999Y1103050
X605999Y1102050
X629499Y1090550
Y1071550
X612399Y1066650
X629999Y1052050
X611399Y1045650
X629999Y1034550
X611399Y1026650
X629999Y1020050
X600999Y1002050
X631999Y1001550
X617699Y988250
X639499Y971150
X616699Y967250
X601499Y954550
X639499Y952150
X616699Y948250
X601499Y937050
Y922550
X603499Y904050
X629499Y868550
X613499Y868050
X612999Y854550
X629499Y853050
X621999Y835050
X606999Y797050
Y778050
X621499Y767150
X607499Y758550
X633499Y750150
X607499Y741050
Y726550
X629099Y714050
X609499Y708050
X622999Y689550
Y672050
X605299Y661750
X631999Y639650
X620499Y623550
Y609050
X625999Y585050
X606499Y584550
X613700Y504600
X621499Y484050
Y466550
Y452050
X621999Y432550
X620999Y411550
X607399Y380250
X635399Y376250
X600299Y365650
X632399Y358750
X628499Y339550
X628200Y320000
X627499Y299550
X627999Y280050
Y262550
Y248050
X605499Y217550
X625499
X623899Y202550
X625499Y183050
X604999Y173750
X624499Y162050
X603999Y152750
X624499Y143050
X603999Y133750
X624999Y123550
X604999Y75350
X624499Y61550
X603999Y54350
X624999Y44550
X603999Y35350
X624499Y23050
X625999Y7050
X608499Y6550
X645499Y7050
X660999
X674999Y20550
X651799Y40650
X675499Y42050
X674999Y59050
X651799Y59650
X675499Y74550
X652799Y80650
X675499Y89050
Y103550
Y121050
X649899Y138350
X674999Y140550
X649899Y157350
X674999Y159550
X650899Y178350
X675999Y180550
X662499Y218050
X677999
X642999
X653999Y286550
X656499Y307050
Y324550
X655999Y344050
X659899Y363250
X643599Y395950
X644599Y416950
X644099Y436450
Y450950
X666999Y476550
Y491050
Y508550
X642499Y525750
X666499Y528050
X643499Y546750
X666499Y547050
X642999Y566250
X667499Y568050
X646999Y584550
X674999Y601550
X640599Y604650
X665999Y623550
X645099Y639150
X673999Y645150
X647499Y657050
X678499Y671050
X647499Y671550
X678499Y688550
X647499Y689050
X648999Y702350
X679299Y703050
X651999Y718350
X647399Y742150
X665499Y766550
X664999Y786050
X653099Y803350
X664999Y805050
X645799Y816650
X665999Y826050
X641599Y843250
X663999Y844550
Y859050
X641599Y862250
X663999Y876550
X642599Y883250
X663499Y896050
Y915050
X664499Y936050
X658999Y959050
X656999Y977550
X678299Y978350
X656999Y992050
X678299Y997350
X656999Y1009550
X673999Y1017550
X656499Y1029050
X673999Y1036550
X656499Y1048050
X674699Y1061450
Y1080450
X669499Y1116550
X674999Y1134950
X641799Y1137650
X667199Y1152850
X650299Y1153150
X668199Y1173850
X651299Y1174150
X650599Y1182050
X670199Y1192750
X651599Y1203050
X671199Y1213750
X668699Y1227650
X657099Y1272850
X657799Y1288450
X672999Y1303450
X656399Y1307050
X671999Y1324950
X665699Y1337250
X677999Y1347550
X654499Y1354050
Y1373050
X654999Y1385050
X652999Y1403550
Y1418050
X678299Y1425050
X652999Y1435550
X659699Y1445950
X665699Y1462250
X656099Y1479550
X672399Y1508750
X673699Y1535350
X643099Y1541350
X662099Y1549650
X652399Y1575850
X670699Y1603150
X652499Y1609550
Y1618550
X671399Y1625350
X649399Y1644950
X657099Y1668850
X674999Y1676550
X656499Y1697050
X642499Y1709050
X675499Y1738050
X665399Y1752350
X675499Y1757050
X675999Y1769050
X650399Y1771250
X659159Y1792278
X642400Y1800100
X644049Y1810834
X659549Y1815384
X640999Y1815550
X669399Y1855350
X667999Y1870950
X645099Y1877550
X661299Y1890050
X674899Y1892350
X676399Y1901150
X645399Y1906150
X661299Y1909050
X674899Y1911350
X661299Y1918050
X674899Y1920350
X646799Y1926450
X644999Y1934050
X660299Y1936550
X673899Y1938850
X644999Y1953050
X660299Y1955550
X673899Y1957850
X660299Y1964550
X645499Y1965050
X673899Y1966850
X678799Y1975750
X659299Y1976250
X643799
X661999Y1986550
X679499Y1987050
X642499
X717999Y1987550
X702499
X696299Y1976250
X685499Y1968050
X709199Y1962950
X685499Y1959050
X698299Y1948050
X711899Y1944050
X685499Y1940050
X695299Y1926450
X716599Y1918450
X696299Y1898850
X705599Y1891850
X686999Y1870250
X706399Y1855850
X690899
X697999Y1844550
X704300Y1828400
X686473Y1818375
X711500Y1817700
X717000Y1812384
X705000Y1811900
X706549Y1793634
X693549Y1793134
X715999Y1772050
X694599Y1768450
X715999Y1763050
X709099Y1751850
X690499Y1744950
X715999Y1744050
X702599Y1730550
X693099Y1722350
X717099Y1702450
X691999Y1660550
X686699Y1638650
X693599Y1602450
X706700Y1579900
X681299Y1579150
X698599Y1568550
X685299Y1551950
X708899Y1549250
X714599Y1533950
X716199Y1503050
X686999Y1468850
X716899Y1459850
X700899Y1450250
X719499Y1446650
X692999Y1421050
Y1406550
X702299Y1404450
X681299Y1393150
X694999Y1388050
X713899Y1386450
X694999Y1379050
X680299Y1365850
X694999Y1360050
X707899Y1346250
X695999Y1323350
X719199Y1322350
X709699Y1264550
X684299Y1249550
X708699Y1243550
X695999Y1235050
Y1217550
X713599Y1214650
X695999Y1203050
X714399Y1199750
X697999Y1184550
X713399Y1178750
X697499Y1172550
X717999Y1169150
X697499Y1153550
X716999Y1148150
X704299Y1132650
X700499Y1118550
X709999Y1105550
X689999
X692499Y1082050
X713499Y1068550
X692499Y1063050
X713999Y1049050
X692999Y1043550
X713999Y1031550
X692999Y1026050
X713999Y1017050
X692999Y1011550
X694999Y993050
X706499Y942550
X688099Y936350
X707399Y918550
X687099Y915350
X707399Y899550
X687099Y896350
X705999Y865550
Y851050
X688099Y844650
X707999Y832550
X687099Y823650
X706999Y811550
X687099Y804650
X706999Y792550
X685999Y780050
X707499Y773050
X694599Y763450
X710899Y751150
X696299Y741850
X716599Y736850
X681899Y713650
X702999Y688050
Y670550
Y656050
X693999Y648150
X717099Y636050
X690499Y623050
X699999Y610050
X691899Y588850
X692399Y569350
X713099Y561550
X691399Y548350
X713599Y542050
X712599Y521050
X695499
X695999Y501550
X713199Y489450
X694999Y480550
X713199Y474950
X713699Y455450
X712699Y434450
X711499Y344550
X683999Y340050
X711999Y325050
X682999Y319050
X711999Y307550
X682999Y300050
X711999Y293050
X680500Y280700
X683499Y263050
X711499Y252550
X683499Y248550
X711999Y218050
X688999Y196550
X700699Y181750
X699699Y160750
Y141750
X695999Y102650
X694999Y81650
Y62650
X697999Y7050
X680499Y6550
X712499Y6050
X729999Y6550
X749499
X725499Y23550
X757499Y44050
X725999Y45050
X751499Y48350
X725499Y62050
X757499Y63050
X725999Y77550
X758499Y84050
X725999Y92050
Y106550
X752099Y112150
X725999Y124050
X738199Y137450
X725499Y143550
X753999Y154550
X757999
X753999Y159050
X757999
X725499Y162550
X726499Y183550
X728899Y204550
X749499Y218550
X729499
X723200Y275500
X751539Y313984
X755499Y314550
X751499Y318050
X755346Y319149
X748000Y357500
X749899Y398550
X750899Y419550
X750399Y439050
Y453550
X737999Y467050
X738999Y488050
X755199Y488150
X738499Y507550
X756199Y509150
X738499Y522050
X755699Y528650
X738499Y539550
X737999Y559050
X754499Y564650
X731499Y572050
X755499Y585650
X731499Y586550
Y604050
X754999Y605150
X721499Y617550
X744999Y626550
X729699Y640350
X723499Y654850
X747999Y670750
X751499Y679148
X757400Y686300
X739399Y688150
X754999Y694050
X749999Y700050
X720899Y712250
X727099Y715050
X744999Y715550
X749499Y716050
X745499Y720050
X749999
X732499Y729250
X750000Y755500
X733799Y761450
X723999Y783350
X743099Y785350
X723999Y802350
X751999Y817050
X724999Y823350
X751499Y836550
X728499Y841850
X751499Y855550
X729999Y862850
Y881850
X751599Y887350
X730999Y902850
X751599Y906350
X752599Y927350
X723699Y936250
X749999Y946550
X723699Y955250
X749999Y965550
X724699Y976250
X750999Y986550
X751399Y1004550
Y1023550
X734999Y1030550
Y1045050
X752399Y1052550
X734999Y1062550
X753999Y1100050
X727499Y1106050
X748499Y1111550
X748999Y1115550
X720499Y1118550
X755499Y1119050
X737999
X749999Y1119550
X727499Y1132650
X747000Y1159000
X737999Y1159550
Y1178550
Y1187550
X758799Y1190150
Y1199150
X735999Y1206050
X756799Y1217650
X735999Y1220550
X725499Y1231650
X756799Y1232150
X757399Y1239650
X725499Y1250650
X740499Y1252550
X757399Y1258650
X725499Y1259650
X757399Y1267650
X740499Y1270050
X723499Y1278150
X755399Y1286150
X723499Y1292650
X740799Y1298750
X755399Y1300650
X742099Y1320650
X739199Y1348950
X734199Y1373850
X736199Y1399050
X721899Y1419050
X754999Y1420050
X737799Y1428350
X754999Y1437550
X741099Y1450250
X729199Y1492750
X741099Y1498150
X755499Y1507550
X747199Y1509150
X751000Y1517000
Y1521000
X757500Y1522500
X751000Y1525000
X735799Y1533650
X742000Y1560000
X734499Y1563550
X722199Y1564250
X743400Y1578700
X751300Y1604900
X719999Y1605050
X732999Y1620050
X738799Y1677250
X756299Y1679050
X727399Y1694350
X750099Y1694950
X756499Y1712150
X739199Y1716750
X721199Y1723750
X747499Y1734350
X751899Y1752150
X729999Y1756450
X756900Y1766000
X752900
X747799Y1766750
X753558Y1769946
X757518Y1770517
X751999Y1775550
X755999
X729499Y1778750
X752657Y1779496
X756617Y1780067
X744049Y1791634
X753949Y1798194
X740549Y1802634
Y1810384
X747599Y1844250
X728099Y1844750
X725899Y1855350
X743399Y1855850
X723199Y1867950
X744699Y1868450
X758399Y1868350
X732999Y1868550
X732199Y1878750
X753699Y1879250
X728299Y1888850
X743799
X739799Y1902150
X755299
X728799Y1908150
X755500Y1914500
X736799Y1919450
X728799Y1933050
X730499Y1954650
X750000Y1965500
X721499Y1974550
X737499Y1987050
X754999Y1987550
X777499
X792999
X789299Y1983850
X775814Y1975699
X784016Y1975708
X771814Y1975713
X783814Y1971713
Y1967213
X774499Y1930050
X768999
X773999Y1923550
X767999Y1923050
X795499Y1922050
X795501Y1917696
X768499Y1917550
X775999Y1916050
X795493Y1913696
X790499Y1913050
X795526Y1909696
X774499Y1908050
X765999
X783499Y1907050
X780799Y1888850
X763299Y1888350
X769199Y1879250
X788699Y1878750
X797199Y1868450
X779699Y1867950
X791799Y1855850
X763899
X779399
X765099Y1844750
X785599
X767159Y1792364
X787900Y1758800
X765600Y1756800
X779899Y1748150
X794499Y1734550
X770099Y1730350
X779999Y1717050
X770399Y1699650
X783499Y1699050
X782999Y1687050
Y1668050
X765099Y1664950
X776999Y1647650
X797299Y1646650
X773827Y1569796
X782827
X778327
X785827Y1565796
X773327
X785827Y1561296
X795999Y1518550
Y1514050
Y1509550
X773499Y1509050
X769499
X786999Y1506550
X795999Y1504550
X780499Y1500050
X770999
X786500Y1488600
X779000Y1488400
X769300Y1488100
X771399Y1474550
X781999Y1434650
X763399Y1401450
X773999Y1393450
X779399Y1361850
X762499Y1353050
X798299Y1344250
X762499Y1335550
X795299Y1326650
X791999Y1294450
X788999Y1278150
X789499Y1257050
Y1239550
Y1225050
X791499Y1206550
X790999Y1194550
Y1175550
X775833Y1165892
X780333
X771333
X783333Y1161892
X771333
X783333Y1157392
X773499Y1105050
X769499
X773499Y1101050
X769499
X789499Y1099550
X798499Y1097566
X783999Y1096550
X760999Y1095550
X777899Y1028050
X776899Y1007050
Y988050
X773199Y960650
X772199Y939650
Y920650
X776199Y879250
X775199Y858250
Y839250
X778999Y806950
X763099Y796350
X771196Y764382
X775696
X780196
X799385Y761436
X783196Y760382
X771196
X783196Y755882
X794331Y711853
Y707353
X766499Y705550
X794331Y702853
X782999Y699550
X766499Y699050
X794331Y698353
X771800Y686600
X798000Y686400
X786500Y686100
X777499Y664550
X794999
X764599Y655750
X785499Y641050
X777499Y638050
X789999Y602050
Y584550
Y570050
X775499Y553550
X774499Y532550
Y513550
X774999Y494050
Y476550
Y462050
X772478Y363924
X781478
X776978
X784478Y359924
X772478
X784478Y355424
X796873Y307571
Y303071
Y298571
Y294071
X786499Y219050
X766999
X779399Y200550
X797999Y187050
X760799Y181950
X796999Y166050
Y147050
X767399Y140150
X797499Y127550
X796599Y123450
X797499Y110050
X778399Y105250
X797499Y95550
Y81050
X775399Y80250
X796999Y65550
X774399Y54050
X797499Y48550
X796999Y27050
X763399Y24150
X764999Y6550
X784499Y6050
X818999
X836499Y6550
X801999
X824899Y25150
X817599Y43750
X813299Y49350
Y68350
X838999Y85050
X814299Y89350
X837999Y91050
X838499Y99550
Y107050
X813299Y110850
X839499Y119050
X805899Y126150
X821199Y137450
X837499Y138550
X838499Y145050
X800999Y216550
X809373Y292571
Y297571
X808999Y303050
X809373Y307571
X838999Y313550
X821499Y314050
X838499Y352050
X839299Y390950
X819299Y394250
X839299Y409950
X819299Y413250
X820299Y434250
X802999Y466050
X803999Y487050
X824899Y500450
X803499Y506550
Y521050
X825899Y521450
X803499Y538550
X825399Y540950
X834599Y543050
X802999Y558050
X835599Y564050
X814499Y569550
X835099Y583550
X814499Y584050
Y601550
X806300Y670600
X806999Y697050
X806831Y701853
Y706853
Y711853
X836149Y714050
X837799Y754150
X835999Y767050
X811499Y767550
X835999Y781550
X811499Y782050
X835999Y799050
X811499Y799550
X802499Y814550
X801999Y834050
X825199Y850850
X801999Y853050
X827699Y873450
X802999Y874050
X827699Y892450
X800999Y892550
Y907050
X828699Y913450
X800999Y924550
X800499Y944050
Y963050
X826999Y963150
Y982150
X801499Y984050
X827999Y1003150
X800999Y1005550
Y1020050
Y1037550
X811499Y1097050
X807499
X802499Y1097566
X807341Y1101216
X806999Y1106050
X807341Y1111216
Y1116216
X836149Y1118550
X808299Y1175850
X831499Y1181550
X806599Y1189750
X831499Y1200550
Y1209550
X803599Y1211050
X829499Y1228050
X810199Y1229350
X829499Y1242550
X810199Y1248350
Y1257350
X828199Y1267850
X808199Y1275850
Y1290350
X826199Y1294450
X831499Y1324950
X822199Y1335250
X799999Y1340550
X819199Y1353550
X799999Y1358050
X825500Y1379000
X806499Y1390550
X834499Y1397550
X806499Y1408050
X836600Y1416500
X803299Y1426650
X805899Y1464250
X801300Y1489000
X809245Y1503722
Y1508722
X808999Y1513550
X809245Y1518722
X839499Y1523550
X839899Y1562050
X825999Y1578050
X813300Y1604100
X826499Y1609050
X803599Y1618350
X827199Y1622750
X814599Y1642650
X837199Y1660550
X802899Y1670550
X823499Y1674050
X839199Y1683550
X823499Y1693050
X808899Y1698450
X823499Y1702050
X829200Y1719800
X824100Y1719900
X819400Y1721900
X819200Y1727100
X808299Y1755250
X827999Y1791550
X801099Y1844750
X809299Y1856350
X829799
X833199Y1868450
X818900Y1870800
X833100Y1878500
X806199Y1879250
X807936Y1910365
Y1914865
X808005Y1918865
X807997Y1922865
X838999Y1928550
X813599Y1979950
X829499Y1980250
X812499Y1987050
X829999Y1987550
X864999Y1987050
X849499
X868699Y1983250
X850499Y1977950
X879399Y1974550
X840999Y1970550
X849999
X856999Y1970050
X865200Y1968000
X873399Y1963650
X864414Y1940050
X861414Y1928550
X843999
X842199Y1879250
X869999Y1855972
X871836Y1840972
X869634Y1826876
X862499Y1823550
X854977Y1818994
X863099Y1813150
X842500Y1799000
X879399Y1798150
X853799Y1790850
X844499Y1788050
X866699Y1770950
X864000Y1748000
X875900Y1709500
X879900Y1709300
X855350Y1703201
X842799Y1701150
X879200Y1698700
X864099Y1683550
X855799Y1658250
X877699Y1646650
X841499Y1638950
X868099Y1635650
X852499Y1621350
X866499Y1612050
X849900Y1605100
X866499Y1603050
X864000Y1578200
X873099Y1572550
X850099Y1572250
X850499Y1562050
X858400Y1561900
X865300Y1557700
X843999Y1523550
X861999Y1522550
X879727Y1463696
X871836Y1450460
Y1435460
Y1420460
X868499Y1410050
Y1392550
X841999Y1358550
X873499Y1356050
X841999Y1341050
X875399Y1322650
X850499Y1300050
X860099Y1295450
X871399Y1291450
X850499Y1282550
X872099Y1268150
X850499Y1268050
X852499Y1249550
X869399Y1243850
X851999Y1237550
X869399Y1229350
X851999Y1218550
X871399Y1210850
Y1201850
X849799Y1199750
X845799Y1190450
X871399Y1182850
X846499Y1170450
X848999Y1158050
X856400Y1157700
X839999Y1157550
X863300Y1153800
X859999Y1118550
X841999
X870298Y1045227
X870468Y1030227
X870777Y1014948
X851999Y983550
X850999Y962550
Y943550
X867199Y941350
X866199Y920350
Y901350
X857099Y873450
X873999Y862550
Y845050
Y830550
X847799Y828250
X859999Y799550
Y782050
Y767550
X846799Y754150
X856299Y753150
X865000Y752100
X866499Y724550
X871385Y719436
X859999Y713050
X871786Y709482
X871499Y689436
X871786Y679436
X860796Y678632
X841000Y671100
X870719Y639705
X870773Y624705
X870719Y609705
X860499Y607550
X861800Y591200
X860699Y565550
X861199Y546050
X860199Y525050
X854999Y464550
X853999Y443550
X840299Y430950
X876799Y426250
X853999Y424550
X875799Y405250
X854499Y405050
Y387550
X875799Y386250
X854499Y373050
X847999Y352550
X858400Y352300
X870600Y346700
X863999Y313550
X879878Y247724
X871786Y233924
Y218924
Y203924
X872100Y132700
X854300Y132600
X875499Y125550
X865499
X845999Y111050
X843499Y82550
X855499Y82050
X876999
X867499
X841499Y71550
X856499Y71050
X866999Y70550
X840999Y62550
X840499Y55050
X839999Y46050
X854499Y39550
X865499
X860799Y24150
X844799Y19850
X855999Y6550
X871499
X890999Y6050
X908499Y6550
X885999Y21150
X909499Y21550
X917499
X902999Y22050
X902499Y35050
X909999Y35550
X916499Y36050
X883999Y39050
X905499Y56550
X904999Y61550
Y67550
X881499Y70550
X904499Y74050
X886499Y99550
X890459Y100116
X890499Y104550
X886499
X890700Y132500
X891999Y146050
X906999Y224150
X887400Y233555
X906999Y243150
X887400Y259700
X907999Y264150
X906399Y295250
Y314250
X907399Y335250
X904999Y370550
Y385050
Y402550
X904499Y422050
Y441050
X884399Y443450
X905499Y462050
X884399Y462450
X885399Y483450
X913699Y484650
Y503650
X914699Y524650
X903999Y574378
X898999Y604550
Y622050
X918999Y641550
X894000Y642400
X881200Y652100
X900999Y652550
X918999Y656050
X887401Y665000
X900999Y670050
X918999Y673550
X918499Y693050
X895999Y702550
X918499Y712050
X895999Y720050
X919499Y733050
X884499Y767050
Y781550
Y799050
X898499Y830050
Y844550
Y862050
X889699Y876050
X919899Y906350
X886999Y907350
X919899Y925350
X886999Y947250
X886919Y1044478
X880033Y1058592
X887400Y1070600
X897299Y1182450
X887999Y1209350
X892499Y1224550
Y1243550
Y1252550
X890499Y1271050
Y1285550
X890999Y1336550
Y1354050
X894499Y1423550
Y1441050
X886913Y1449010
X887499Y1476050
X895499Y1488050
X902759Y1509585
X914599Y1521650
X894499Y1522050
Y1539550
X910899Y1549250
X909700Y1576400
X907500Y1604000
X886900Y1604100
X887299Y1620050
X908899Y1630050
X914899Y1657550
X895999Y1661250
X882999Y1678250
X903599Y1686850
X883900Y1709500
X902900Y1709800
X892700Y1727800
Y1736500
X886400Y1744400
X882200Y1744800
X904814Y1789113
X911299Y1800850
X903299Y1814750
X894999Y1829050
X905299Y1852650
X887499Y1855550
X914999Y1868050
X894000Y1868452
X900299Y1876950
X887401Y1881500
X914999Y1887050
X915499Y1899050
X897299Y1904150
X914899Y1912450
X907599Y1930050
X897599Y1938750
X916599Y1942650
X904299Y1954950
X914899Y1972250
X884499Y1986550
X901999Y1987050
X936999Y1986550
X921499
X956499Y1986050
X930199Y1979550
X953799Y1977950
X946199Y1966650
X931499Y1962050
X955799Y1951950
X930999Y1950050
X945199Y1946350
X947499Y1936050
X930999Y1931050
X938199Y1917150
X954099Y1915450
X955499Y1902050
X937499Y1893850
X955499Y1893050
X937199Y1869950
X922899Y1853650
X928000Y1818500
X932199Y1801850
X934200Y1793500
X941800Y1787700
X954499Y1783550
X941499Y1776250
X949799Y1756250
X958799Y1715750
X931499Y1702050
X955499Y1690850
X922599Y1682150
X941499Y1679550
X940499Y1656950
X957799Y1646950
X923599Y1634350
X944499Y1632650
X950100Y1626100
X925599Y1612050
X933199Y1577550
X925499Y1562550
X924499Y1541550
X943199Y1531650
X924499Y1522550
X944000Y1511300
X951349Y1504800
X924999Y1503050
X951349Y1500300
X951500Y1495300
X958500Y1486800
X924999Y1485550
X958800Y1481500
Y1477000
Y1472500
X924999Y1471050
X952300Y1467500
X952500Y1462300
Y1457800
X926499Y1456550
X952500Y1452800
Y1448300
X952800Y1442000
Y1437500
X925499Y1435550
X946700Y1426500
X925499Y1416550
X925999Y1397050
X944000Y1391900
X943799Y1380850
X925999Y1379550
Y1365050
X952499Y1361850
X943799Y1342950
X928499Y1325350
X951699Y1302750
X926499Y1298550
X950699Y1281750
X925499Y1277550
X950699Y1262750
X925499Y1258550
X951199Y1243250
X925999Y1239050
X951199Y1225750
X925999Y1221550
X951199Y1211250
X925999Y1207050
X951199Y1199250
X925999Y1195050
X950199Y1178250
X924999Y1174050
X950199Y1159250
X924999Y1155050
X950699Y1139750
X925499Y1135550
X950699Y1122250
X925499Y1118050
X950699Y1107750
X925499Y1103550
X921999Y1090550
X949799Y1080950
X920999Y1069550
X949799Y1068950
X920999Y1050550
X948799Y1047950
X921499Y1031050
X948799Y1028950
X921499Y1013550
X949299Y1009450
X921499Y999050
X949299Y991950
Y977450
X920899Y946350
X943499Y937050
X942499Y916050
Y897050
X920399Y886850
X942999Y877550
X920399Y869350
X942999Y860050
X920399Y854850
X942999Y845550
X922399Y836350
X944999Y827050
X921399Y815350
X943999Y806050
X921399Y796350
X943999Y787050
X921899Y776850
X944499Y767550
X921899Y759350
X944499Y750050
X921899Y744850
X944499Y735550
X950799Y691150
X949799Y670150
Y651150
X950299Y631650
X935999Y616050
X950299Y614150
Y599650
X934999Y595050
X952299Y581150
X934999Y576050
X951299Y560150
X935499Y556550
X951299Y541150
X935499Y539050
Y524550
X951799Y521650
X933999Y506550
X951799Y504150
Y489650
X932999Y485550
Y466550
X954799Y451650
X933499Y447050
X954799Y434150
X933499Y429550
X954799Y419650
X933499Y415050
X953299Y401650
X933999Y395550
X952299Y380650
X932999Y374550
X952299Y361650
X932999Y355550
X952799Y342150
X933499Y336050
X952799Y324650
X933499Y318550
X952799Y310150
X933499Y304050
X953299Y290650
X932999Y283050
X952299Y269650
X931999Y262050
X952299Y250650
X931999Y243050
X952799Y231150
X932499Y223550
X952799Y213650
X932499Y206050
X952799Y199150
X932499Y191550
X956099Y181350
X958799Y167350
X939199Y142050
X943499Y78050
Y72550
X942999Y66550
X928999Y65550
X942999Y61550
X928499Y60550
X928999Y56050
X943499Y55050
X928499Y51550
X943499Y48050
X945499Y33550
X940499Y33050
X929999Y32550
X954799Y17850
X941499Y6550
X923999Y6050
X995999
X960999Y6550
X976499
X974699Y21450
X991399Y22450
X977399Y44050
X967499Y47050
X991999Y56050
X967499
Y64050
X974699Y64650
X967999Y73050
Y82050
X983099Y83650
X994399Y101250
X977699Y109150
X981099Y123450
X968399Y137150
X988699Y174350
X967399Y180350
X982999Y189050
Y203550
Y221050
X982499Y240550
Y259550
X983499Y280550
X983999Y301550
Y316050
Y333550
X983499Y353050
Y372050
X984499Y393050
X983999Y412550
Y427050
Y444550
X983499Y464050
X966199Y473350
X983499Y483050
X966199Y492350
X984499Y504050
X967199Y513350
X985999Y522050
Y536550
Y554050
X966799Y566350
X985499Y573550
X966799Y585350
X985499Y592550
X967799Y606350
X986499Y613550
X969499Y639050
Y653550
Y671050
X968999Y690550
Y709550
X969999Y730550
X994999Y733050
X969999Y744250
X994999Y747550
X969999Y758750
X994999Y765050
X969999Y776250
X994499Y784550
X969499Y795750
X994499Y803550
X969499Y814750
X995499Y824550
X970499Y835750
X993499Y843050
X970499Y847750
X993499Y857550
X970499Y862250
X993499Y875050
X970499Y879750
X992999Y894550
X969999Y899250
X992999Y913550
X969999Y918250
X993999Y934550
X970999Y939250
X994499Y941550
Y956050
Y973550
X993999Y993050
X971999Y996550
Y1011050
X993999Y1012050
X971999Y1028550
X994999Y1033050
Y1045050
X971499Y1048050
Y1067050
X972499Y1088050
X998599Y1096450
X975999Y1101050
X998599Y1110950
X975999Y1115550
X998599Y1128450
X975999Y1133050
X998099Y1147950
X975499Y1152550
X998099Y1166950
X975499Y1171550
X999099Y1187950
X976499Y1192550
X999099Y1199950
X976499Y1204550
X999099Y1214450
X976499Y1219050
X999099Y1231950
X976499Y1236550
X998599Y1251450
X975999Y1256050
X998599Y1270450
X975999Y1275050
X999599Y1291450
X976999Y1296050
X965099Y1324350
X996500Y1324800
X975100Y1342600
X976499Y1362550
Y1377050
X992500Y1397300
X964400Y1409700
X994200Y1421500
X962500Y1436500
X972000Y1437500
X962500Y1441000
X972000Y1442000
X962200Y1447300
X971700Y1448300
X962200Y1451800
X971700Y1452800
X962200Y1456800
X971700Y1457800
X962200Y1461300
X971700Y1462300
X962000Y1466500
X971500Y1467500
X973500Y1474000
X966000Y1475000
X973500Y1478500
X966000Y1479500
X973500Y1483000
X966000Y1484000
X973200Y1488300
X965700Y1489300
X960200Y1495300
X972700Y1497300
X960049Y1500300
X972549Y1502300
X960049Y1504800
X972549Y1506800
X962100Y1516000
X973200Y1516400
X967300
X961900Y1522400
X973000Y1522800
X967100
X961400Y1528700
X972500Y1529100
X966600
X961600Y1534400
X966800Y1534800
X972700
X961400Y1540800
X972500Y1541200
X966600
X960900Y1547100
X972000Y1547500
X966100
X961600Y1552900
X966800Y1553300
X972700
X961400Y1559300
X966600Y1559700
X972500
X960900Y1565600
X972000Y1566000
X966100
X961900Y1572400
X973000Y1572800
X967100
X961700Y1578800
X966900Y1579200
X972800
X961200Y1585100
X972300Y1585500
X966400
X961300Y1591600
X972400Y1592000
X966500
X961100Y1598000
X972200Y1598400
X966300
X960600Y1604300
X971700Y1604700
X965800
X989999Y1718050
X993299Y1734350
X965349Y1742000
X994999Y1748950
X976600Y1757100
X976399Y1772250
Y1791150
X971000Y1803000
X993499Y1805550
Y1824550
Y1833550
X995699Y1858950
X971500Y1871500
X966799Y1892150
X974699Y1914450
X991999Y1915750
X992299Y1929050
X980999Y1933350
X971499Y1937050
X987999Y1949050
X971499Y1956050
X989999Y1962650
X971499Y1965050
X987999Y1971950
X994999Y1986550
X973999
X1017999Y1987050
X1005000Y1980500
X1023000Y1973000
X1017499Y1954550
X1002500Y1953500
X1000999Y1946350
X1017999Y1937050
X1001599Y1921450
X1020999Y1912550
Y1897050
X1020499Y1877550
X1011299Y1860650
X1020999Y1860050
X1003599Y1846650
X1022999Y1837050
Y1821550
X1007599Y1818450
X1022499Y1802050
X1009999Y1797450
X1022999Y1784550
X999999Y1775250
X1026899Y1768550
X1015299Y1765950
X1020299Y1746650
X1016899Y1731650
X1008599Y1716050
X1022299Y1715750
X1008999Y1702450
X1024300Y1393600
Y1365200
X1000700Y1358100
X1023300Y1344400
X1022599Y1322950
X1016499Y1301050
X1016999Y1271550
Y1256050
X1016499Y1236550
X1016999Y1219050
X1019499Y1198550
Y1183050
X1018999Y1163550
X1019499Y1146050
X1020499Y1134050
Y1118550
X1019999Y1099050
X1020499Y1081550
X1019999Y1058550
Y1043050
X1019499Y1023550
X1019999Y1006050
Y986550
Y971050
X1019499Y951550
X1019999Y934050
Y917550
X1020499Y900050
Y880550
Y865050
X1019999Y845550
X1020499Y828050
Y809550
X1020999Y792050
Y772550
Y757050
X1020499Y737550
X1020999Y720050
X1020499Y695050
X1020999Y677550
Y658050
Y642550
X1005999Y636350
X1020499Y623050
X1005999Y618850
X1020999Y605550
X1005999Y604350
X1004499Y586350
X1021499Y576050
X1003499Y565350
X1021999Y558550
X1003499Y546350
X1021999Y539050
X1003999Y526850
X1021999Y523550
X1021499Y504050
X1001699Y503350
X1021999Y486550
X1000699Y482350
X1020499Y463550
X1000699Y463350
X1020999Y446050
X1007299Y432450
X1020999Y426550
X1007299Y414950
X1020999Y411050
X1007299Y400450
X1020499Y391550
X1005799Y382450
X1020999Y374050
X1004799Y361450
Y342450
X1020499Y341550
X1020999Y324050
X1005299Y322950
Y305450
X1020999Y304550
X1005299Y290950
X1020999Y289050
X1005799Y271450
X1020499Y269550
X1020999Y252050
X1004799Y250450
Y231450
X1020999Y230550
X1021499Y213050
X1005299Y211950
Y194450
X1021499Y193550
X1005299Y179950
X1021499Y178050
X1020999Y158550
X1021499Y141050
X1020499Y122550
X1010599Y115550
X1020999Y105050
Y85550
X1005299Y71350
X1020999Y70050
X1020499Y50550
X1002699Y40050
X1020999Y33050
X1022000Y15500
X1013499Y6550
T03
X994098Y149601
X271657Y267711
X29532Y309561
X271657Y673223
X994098
X994099Y1068892
X271657Y1078734
X29532Y1029522
X271657Y1484246
Y1889758
X17720Y1903144
T04
X129920Y17716
X994093Y1889751
T05
X78150Y28858
Y178464
Y434370
Y583976
Y839882
Y989488
Y1245394
Y1395000
Y1650906
Y1800512
X158071Y1963268
Y1813662
Y1557756
Y1408150
Y1152244
Y1002638
Y746732
Y597126
Y341220
Y191614
X886417
Y341220
Y597126
Y746732
Y1002638
Y1152244
Y1408150
Y1557756
Y1813662
Y1963268
T06
X-39052Y28742
X-43327Y310478
X-39686Y917251
X-38801Y1082342
X-44886Y1294251
X-43103Y1928864
X1074813Y1957551
X1076613Y1740651
X1074813Y1348051
X1071932Y32074
T07
X9843Y153168
Y265767
Y353144
Y717711
Y762617
Y875216
Y1137420
Y1250019
Y1337396
Y1701963
Y1746869
Y1859468
T08
X1019291Y1416024
Y1694212
M30
